G04 ================== begin FILE IDENTIFICATION RECORD ==================*
G04 Layout Name:  9052_F0T_PDB_Converter_Brick_F_V03_1208_1600.brd*
G04 Film Name:    ssb*
G04 File Format:  Gerber RS274X*
G04 File Origin:  Cadence Allegro 17.2-S081*
G04 Origin Date:  Wed Dec 21 09:54:59 2022*
G04 *
G04 Layer:  DRAWING FORMAT/TITLE_BLOCK_A*
G04 Layer:  BOARD GEOMETRY/DESIGN_OUTLINE*
G04 Layer:  BOARD GEOMETRY/CUTOUT*
G04 Layer:  BOARD GEOMETRY/OUTLINE*
G04 Layer:  DRAWING FORMAT/TITLE_BLOCK*
G04 Layer:  MANUFACTURING/TP_TEXT_BOTTOM*
G04 Layer:  REF DES/SILKSCREEN_BOTTOM*
G04 Layer:  PACKAGE GEOMETRY/SILKSCREEN_BOTTOM*
G04 Layer:  MANUFACTURING/PHOTOPLOT_OUTLINE*
G04 Layer:  DRAWING FORMAT/TITLE_DATA_SSB*
G04 Layer:  BOARD GEOMETRY/SILKSCREEN_BOTTOM*
G04 *
G04 Offset:    (0.00 0.00)*
G04 Mirror:    No*
G04 Mode:      Positive*
G04 Rotation:  0*
G04 FullContactRelief:  No*
G04 UndefLineWidth:     6.00*
G04 ================== end FILE IDENTIFICATION RECORD ====================*
%FSLAX25Y25*MOIN*%
%IR0*IPPOS*OFA0.00000B0.00000*MIA0B0*SFA1.00000B1.00000*%
%ADD10C,.006*%
G75*
%LPD*%
G75*
G36*
G01X789500Y361516D02*
Y357516D01*
X785500Y359516D01*
X789500Y361516D01*
G37*
G36*
G01X815600Y308000D02*
X812600Y309500D01*
Y306500D01*
X815600Y308000D01*
G37*
G36*
G01X834262Y342059D02*
X838262Y344059D01*
Y340059D01*
X834262Y342059D01*
G37*
G36*
G01X858600Y339500D02*
Y337500D01*
X855600Y338500D01*
X858600Y339500D01*
G37*
G36*
G01X883800Y318359D02*
X886800Y316859D01*
Y319859D01*
X883800Y318359D01*
G37*
G36*
G01X913762Y309559D02*
X917762Y311559D01*
Y307559D01*
X913762Y309559D01*
G37*
G36*
G01X924800Y334400D02*
X922800D01*
X923800Y337400D01*
X924800Y334400D01*
G37*
G36*
G01X927935Y341864D02*
Y339404D01*
X930115Y340696D01*
X927935Y341864D01*
G37*
G36*
G01X1070173Y94752D02*
Y106248D01*
X1067024D01*
Y94752D01*
X1070173D01*
G37*
G36*
G01X1124173Y101252D02*
Y112748D01*
X1121024D01*
Y101252D01*
X1124173D01*
G37*
G54D10*
G01X-297025Y-1013390D02*
Y1828909D01*
X3691357D01*
Y-1013390D01*
X-297025D01*
G01X4093Y-769672D02*
Y-844672D01*
X504093D01*
Y-769672D01*
X4093D01*
G01X0Y518622D02*
G03X11811Y506811I11811J0D01*
G01X37795D01*
G02X39764Y504843I0J-1968D01*
G01Y459567D01*
G02X37795Y457598I-1969J0D01*
G01X11811D01*
G03X0Y445787I0J-11811D01*
G01Y136102D01*
G03X11811Y124291I11811J0D01*
G01X37795D01*
G02X39764Y122323I0J-1969D01*
G01Y77047D01*
G02X37795Y75079I-1969J1D01*
G01X11811D01*
G03X0Y63268I0J-11811D01*
G01Y19685D01*
G03X19685Y0I19685J0D01*
G01X1271654D01*
G03X1291339Y19685I0J19685D01*
G01Y559055D01*
G03X1271654Y578740I-19685J0D01*
G01X19685D01*
G03X0Y559055I0J-19685D01*
G01Y518622D01*
G01X16093Y-834672D02*
Y-839672D01*
G01X14636Y-834672D02*
X17550D01*
G01X22460Y-839672D02*
X19926D01*
Y-834672D01*
X22460D01*
G01X21446Y-837089D02*
X19926D01*
G01X25026Y-834672D02*
Y-839672D01*
X27560D01*
G01X31393Y-839839D02*
X31266Y-839755D01*
Y-839589D01*
X31393Y-839505D01*
X31520Y-839589D01*
Y-839755D01*
X31393Y-839839D01*
G01Y-837589D02*
X31266Y-837505D01*
Y-837339D01*
X31393Y-837255D01*
X31520Y-837339D01*
Y-837505D01*
X31393Y-837589D01*
G01X36176Y-841339D02*
X35543Y-840505D01*
X35226Y-839672D01*
Y-836339D01*
X35543Y-835505D01*
X36176Y-834672D01*
G01X41593D02*
X41086Y-834839D01*
X40706Y-835255D01*
X40453Y-835755D01*
X40263Y-836422D01*
X40200Y-837172D01*
X40263Y-837922D01*
X40453Y-838589D01*
X40706Y-839089D01*
X41086Y-839505D01*
X41593Y-839672D01*
X42100Y-839505D01*
X42480Y-839089D01*
X42733Y-838589D01*
X42923Y-837922D01*
X42986Y-837172D01*
X42923Y-836422D01*
X42733Y-835755D01*
X42480Y-835255D01*
X42100Y-834839D01*
X41593Y-834672D01*
G01X45300Y-838672D02*
X45680Y-839255D01*
X46186Y-839589D01*
X46756Y-839672D01*
X47263Y-839589D01*
X47770Y-839172D01*
X48086Y-838672D01*
X48150Y-838172D01*
X48023Y-837589D01*
X47580Y-837172D01*
X47136Y-837005D01*
X46566D01*
G01X47136D02*
X47516Y-836755D01*
X47833Y-836339D01*
X47960Y-835839D01*
X47833Y-835339D01*
X47516Y-834922D01*
X46946Y-834672D01*
X46376Y-834755D01*
X45806Y-835089D01*
G01X52110Y-841339D02*
X52743Y-840505D01*
X53060Y-839672D01*
Y-836339D01*
X52743Y-835505D01*
X52110Y-834672D01*
G01X55500Y-838672D02*
X55880Y-839255D01*
X56386Y-839589D01*
X56956Y-839672D01*
X57463Y-839589D01*
X57970Y-839172D01*
X58286Y-838672D01*
X58350Y-838172D01*
X58223Y-837589D01*
X57780Y-837172D01*
X57336Y-837005D01*
X56766D01*
G01X57336D02*
X57716Y-836755D01*
X58033Y-836339D01*
X58160Y-835839D01*
X58033Y-835339D01*
X57716Y-834922D01*
X57146Y-834672D01*
X56576Y-834755D01*
X56006Y-835089D01*
G01X60790Y-835505D02*
X61170Y-835005D01*
X61613Y-834755D01*
X62120Y-834672D01*
X62753Y-834839D01*
X63196Y-835255D01*
X63323Y-835755D01*
X63260Y-836255D01*
X63006Y-836672D01*
X61740Y-837505D01*
X61170Y-838089D01*
X60790Y-838922D01*
X60663Y-839672D01*
X63323D01*
G01X66966D02*
X67093Y-838589D01*
X67283Y-837672D01*
X67536Y-836839D01*
X67853Y-835922D01*
X68360Y-834672D01*
X65826D01*
G01X71370Y-838005D02*
X73016D01*
G01X76090Y-835505D02*
X76470Y-835005D01*
X76913Y-834755D01*
X77420Y-834672D01*
X78053Y-834839D01*
X78496Y-835255D01*
X78623Y-835755D01*
X78560Y-836255D01*
X78306Y-836672D01*
X77040Y-837505D01*
X76470Y-838089D01*
X76090Y-838922D01*
X75963Y-839672D01*
X78623D01*
G01X81000Y-838672D02*
X81380Y-839255D01*
X81886Y-839589D01*
X82456Y-839672D01*
X82963Y-839589D01*
X83470Y-839172D01*
X83786Y-838672D01*
X83850Y-838172D01*
X83723Y-837589D01*
X83280Y-837172D01*
X82836Y-837005D01*
X82266D01*
G01X82836D02*
X83216Y-836755D01*
X83533Y-836339D01*
X83660Y-835839D01*
X83533Y-835339D01*
X83216Y-834922D01*
X82646Y-834672D01*
X82076Y-834755D01*
X81506Y-835089D01*
G01X88253Y-839672D02*
Y-834672D01*
X85910Y-838255D01*
X89076D01*
G01X91200Y-838922D02*
X91580Y-839339D01*
X92023Y-839589D01*
X92593Y-839672D01*
X93163Y-839505D01*
X93606Y-839172D01*
X93923Y-838589D01*
X93986Y-837922D01*
X93860Y-837255D01*
X93543Y-836839D01*
X93100Y-836505D01*
X92656Y-836422D01*
X92213Y-836505D01*
X91643Y-836839D01*
X91833Y-834672D01*
X93543D01*
G01X101590Y-839672D02*
Y-834672D01*
X103996D01*
G01X103110Y-837089D02*
X101590D01*
G01X106310Y-839672D02*
X107893Y-834672D01*
X109476Y-839672D01*
G01X108906Y-837922D02*
X106880D01*
G01X111663Y-839672D02*
X114323Y-834672D01*
G01X111663D02*
X114323Y-839672D01*
G01X118093Y-839839D02*
X117966Y-839755D01*
Y-839589D01*
X118093Y-839505D01*
X118220Y-839589D01*
Y-839755D01*
X118093Y-839839D01*
G01Y-837589D02*
X117966Y-837505D01*
Y-837339D01*
X118093Y-837255D01*
X118220Y-837339D01*
Y-837505D01*
X118093Y-837589D01*
G01X122876Y-841339D02*
X122243Y-840505D01*
X121926Y-839672D01*
Y-836339D01*
X122243Y-835505D01*
X122876Y-834672D01*
G01X128293D02*
X127786Y-834839D01*
X127406Y-835255D01*
X127153Y-835755D01*
X126963Y-836422D01*
X126900Y-837172D01*
X126963Y-837922D01*
X127153Y-838589D01*
X127406Y-839089D01*
X127786Y-839505D01*
X128293Y-839672D01*
X128800Y-839505D01*
X129180Y-839089D01*
X129433Y-838589D01*
X129623Y-837922D01*
X129686Y-837172D01*
X129623Y-836422D01*
X129433Y-835755D01*
X129180Y-835255D01*
X128800Y-834839D01*
X128293Y-834672D01*
G01X132000Y-838672D02*
X132380Y-839255D01*
X132886Y-839589D01*
X133456Y-839672D01*
X133963Y-839589D01*
X134470Y-839172D01*
X134786Y-838672D01*
X134850Y-838172D01*
X134723Y-837589D01*
X134280Y-837172D01*
X133836Y-837005D01*
X133266D01*
G01X133836D02*
X134216Y-836755D01*
X134533Y-836339D01*
X134660Y-835839D01*
X134533Y-835339D01*
X134216Y-834922D01*
X133646Y-834672D01*
X133076Y-834755D01*
X132506Y-835089D01*
G01X138810Y-841339D02*
X139443Y-840505D01*
X139760Y-839672D01*
Y-836339D01*
X139443Y-835505D01*
X138810Y-834672D01*
G01X142200Y-838672D02*
X142580Y-839255D01*
X143086Y-839589D01*
X143656Y-839672D01*
X144163Y-839589D01*
X144670Y-839172D01*
X144986Y-838672D01*
X145050Y-838172D01*
X144923Y-837589D01*
X144480Y-837172D01*
X144036Y-837005D01*
X143466D01*
G01X144036D02*
X144416Y-836755D01*
X144733Y-836339D01*
X144860Y-835839D01*
X144733Y-835339D01*
X144416Y-834922D01*
X143846Y-834672D01*
X143276Y-834755D01*
X142706Y-835089D01*
G01X147616Y-839089D02*
X148060Y-839505D01*
X148566Y-839672D01*
X149073Y-839505D01*
X149516Y-839005D01*
X149833Y-838255D01*
X149960Y-837505D01*
Y-836589D01*
X149833Y-835839D01*
X149516Y-835172D01*
X149136Y-834839D01*
X148693Y-834672D01*
X148186Y-834839D01*
X147806Y-835172D01*
X147553Y-835672D01*
X147426Y-836339D01*
X147553Y-836922D01*
X147870Y-837505D01*
X148250Y-837839D01*
X148693Y-837922D01*
X149200Y-837755D01*
X149580Y-837339D01*
X149960Y-836589D01*
G01X153666Y-839672D02*
X153793Y-838589D01*
X153983Y-837672D01*
X154236Y-836839D01*
X154553Y-835922D01*
X155060Y-834672D01*
X152526D01*
G01X158070Y-838005D02*
X159716D01*
G01X162600Y-838672D02*
X162980Y-839255D01*
X163486Y-839589D01*
X164056Y-839672D01*
X164563Y-839589D01*
X165070Y-839172D01*
X165386Y-838672D01*
X165450Y-838172D01*
X165323Y-837589D01*
X164880Y-837172D01*
X164436Y-837005D01*
X163866D01*
G01X164436D02*
X164816Y-836755D01*
X165133Y-836339D01*
X165260Y-835839D01*
X165133Y-835339D01*
X164816Y-834922D01*
X164246Y-834672D01*
X163676Y-834755D01*
X163106Y-835089D01*
G01X167890Y-837589D02*
X168333Y-837005D01*
X168713Y-836672D01*
X169220Y-836505D01*
X169663Y-836672D01*
X169980Y-837005D01*
X170233Y-837505D01*
X170296Y-838089D01*
X170233Y-838589D01*
X169980Y-839089D01*
X169600Y-839505D01*
X169156Y-839672D01*
X168650Y-839505D01*
X168206Y-839005D01*
X167953Y-838255D01*
X167890Y-837422D01*
X168016Y-836339D01*
X168206Y-835755D01*
X168523Y-835172D01*
X168966Y-834755D01*
X169410Y-834672D01*
X169853Y-834839D01*
X170170Y-835255D01*
G01X174193Y-839672D02*
Y-834672D01*
X173433Y-835672D01*
G01Y-839672D02*
X174953D01*
G01X180053D02*
Y-834672D01*
X177710Y-838255D01*
X180876D01*
G01X118110Y41339D02*
X106299D01*
X32015Y37415D01*
G02Y57073I-519J9829D01*
G01X106299Y53150D01*
X118110D01*
G02Y41339I0J-5905D01*
G01Y53150D02*
G02Y41339I0J-5905D01*
G01X106299D01*
X32015Y37415D01*
G02Y57073I-519J9829D01*
G01X106299Y53150D01*
X118110D01*
G01X19921Y218504D02*
G02Y209843I0J-4330D01*
G02Y218504I0J4331D01*
G01Y209843D02*
G03Y218504I0J4331D01*
G03Y209843I0J-4330D01*
G01Y372047D02*
G02Y363386I0J-4330D01*
G02Y372047I0J4330D01*
G01Y363386D02*
G03Y372047I0J4330D01*
G03Y363386I0J-4330D01*
G01X32015Y545262D02*
X106299Y541339D01*
X118110D01*
G02Y529528I0J-5906D01*
G01X106299D01*
X32015Y525604D01*
G02Y545262I-519J9829D01*
G01D02*
G03Y525604I-519J-9829D01*
G01X106299Y529528D01*
X118110D01*
G03Y541339I0J5905D01*
G01X106299D01*
X32015Y545262D01*
G01X60630Y107520D02*
G02Y91929I0J-7796D01*
G02Y107520I0J7796D01*
G01Y91929D02*
G02Y107520I0J7796D01*
G02Y91929I0J-7796D01*
G01Y490000D02*
G02Y474409I0J-7796D01*
G02Y490000I0J7796D01*
G01Y474409D02*
G02Y490000I0J7796D01*
G02Y474409I0J-7796D01*
G01X82795Y107520D02*
G02Y91929I0J-7796D01*
G02Y107520I0J7796D01*
G01Y91929D02*
G02Y107520I0J7796D01*
G02Y91929I0J-7796D01*
G01Y490000D02*
G02Y474409I0J-7796D01*
G02Y490000I0J7796D01*
G01Y474409D02*
G02Y490000I0J7796D01*
G02Y474409I0J-7796D01*
G01X108858Y107520D02*
G02Y91929I0J-7796D01*
G02Y107520I0J7796D01*
G01Y91929D02*
G02Y107520I0J7796D01*
G02Y91929I0J-7796D01*
G01Y490000D02*
G02Y474409I0J-7796D01*
G02Y490000I0J7796D01*
G01Y474409D02*
G02Y490000I0J7796D01*
G02Y474409I0J-7796D01*
G01X178819Y281339D02*
G02Y273071I0J-4134D01*
G02Y281339I0J4134D01*
G01Y273071D02*
G03Y281339I0J4134D01*
G03Y273071I0J-4134D01*
G01X199093Y-769672D02*
Y-844672D01*
G01Y-819672D02*
X302093D01*
Y-794672D01*
G01X199093D02*
X302093D01*
G01X193819Y281339D02*
G02Y273071I0J-4134D01*
G02Y281339I0J4134D01*
G01Y273071D02*
G03Y281339I0J4134D01*
G03Y273071I0J-4134D01*
G01Y480354D02*
G02Y474055I0J-3149D01*
G02Y480354I0J3149D01*
G01Y474055D02*
G03Y480354I0J3149D01*
G03Y474055I0J-3149D01*
G01X223819Y480354D02*
G02Y474055I0J-3149D01*
G02Y480354I0J3149D01*
G01Y474055D02*
G03Y480354I0J3149D01*
G03Y474055I0J-3149D01*
G01X268819Y281339D02*
G02Y273071I0J-4134D01*
G02Y281339I0J4134D01*
G01X253819D02*
G02Y273071I0J-4134D01*
G02Y281339I0J4134D01*
G01X268819Y273071D02*
G03Y281339I0J4134D01*
G03Y273071I0J-4134D01*
G01X253819D02*
G03Y281339I0J4134D01*
G03Y273071I0J-4134D01*
G01Y480354D02*
G02Y474055I0J-3149D01*
G02Y480354I0J3149D01*
G01Y474055D02*
G03Y480354I0J3149D01*
G03Y474055I0J-3149D01*
G01X309600Y-829672D02*
Y-824672D01*
X310866D01*
X311373Y-824922D01*
X311753Y-825255D01*
X312070Y-825755D01*
X312323Y-826339D01*
X312386Y-827172D01*
X312323Y-828005D01*
X312070Y-828589D01*
X311753Y-829089D01*
X311373Y-829422D01*
X310866Y-829672D01*
X309600D01*
G01X314510D02*
X316093Y-824672D01*
X317676Y-829672D01*
G01X317106Y-827922D02*
X315080D01*
G01X321193Y-824672D02*
Y-829672D01*
G01X319736Y-824672D02*
X322650D01*
G01X327560Y-829672D02*
X325026D01*
Y-824672D01*
X327560D01*
G01X326546Y-827089D02*
X325026D01*
G01X331393Y-829839D02*
X331266Y-829755D01*
Y-829589D01*
X331393Y-829505D01*
X331520Y-829589D01*
Y-829755D01*
X331393Y-829839D01*
G01Y-827589D02*
X331266Y-827505D01*
Y-827339D01*
X331393Y-827255D01*
X331520Y-827339D01*
Y-827505D01*
X331393Y-827589D01*
G01X304093Y-769672D02*
Y-844672D01*
G01X302093Y-769672D02*
Y-844672D01*
G01X304093Y-819672D02*
X504093D01*
G01X309726Y-804672D02*
Y-799672D01*
X311246D01*
X311753Y-799922D01*
X312133Y-800505D01*
X312260Y-801172D01*
X312133Y-801839D01*
X311816Y-802339D01*
X311246Y-802589D01*
X309726D01*
G01X314953Y-804839D02*
X317233Y-799672D01*
G01X319736Y-804672D02*
Y-799672D01*
X322650Y-804672D01*
Y-799672D01*
G01X326293Y-804839D02*
X326166Y-804755D01*
Y-804589D01*
X326293Y-804505D01*
X326420Y-804589D01*
Y-804755D01*
X326293Y-804839D01*
G01Y-802589D02*
X326166Y-802505D01*
Y-802339D01*
X326293Y-802255D01*
X326420Y-802339D01*
Y-802505D01*
X326293Y-802589D01*
G01X304093Y-794672D02*
X504093D01*
G01X309726Y-779672D02*
Y-774672D01*
X311246D01*
X311753Y-774922D01*
X312133Y-775505D01*
X312260Y-776172D01*
X312133Y-776839D01*
X311816Y-777339D01*
X311246Y-777589D01*
X309726D01*
G01X314826Y-779672D02*
Y-774672D01*
X316410D01*
X316916Y-774922D01*
X317233Y-775255D01*
X317360Y-775922D01*
X317233Y-776589D01*
X316853Y-777005D01*
X316410Y-777255D01*
X314826D01*
G01X316410D02*
X317360Y-779672D01*
G01X321193D02*
X320686Y-779589D01*
X320243Y-779255D01*
X319863Y-778755D01*
X319610Y-778172D01*
X319483Y-777505D01*
Y-776839D01*
X319610Y-776172D01*
X319863Y-775589D01*
X320243Y-775089D01*
X320686Y-774755D01*
X321193Y-774672D01*
X321700Y-774755D01*
X322143Y-775089D01*
X322523Y-775589D01*
X322776Y-776172D01*
X322903Y-776839D01*
Y-777505D01*
X322776Y-778172D01*
X322523Y-778755D01*
X322143Y-779255D01*
X321700Y-779589D01*
X321193Y-779672D01*
G01X325026Y-778672D02*
X325343Y-779172D01*
X325723Y-779505D01*
X326166Y-779672D01*
X326673Y-779505D01*
X327053Y-779172D01*
X327433Y-778672D01*
X327560Y-778005D01*
Y-774672D01*
G01X332660Y-779672D02*
X330126D01*
Y-774672D01*
X332660D01*
G01X331646Y-777089D02*
X330126D01*
G01X337886Y-775089D02*
X337506Y-774839D01*
X337063Y-774672D01*
X336556D01*
X335986Y-774922D01*
X335543Y-775339D01*
X335226Y-775839D01*
X334973Y-776672D01*
X334910Y-777422D01*
X335036Y-778172D01*
X335226Y-778672D01*
X335606Y-779172D01*
X336050Y-779505D01*
X336493Y-779672D01*
X336936D01*
X337380Y-779505D01*
X337760Y-779255D01*
X338076Y-778922D01*
G01X341593Y-774672D02*
Y-779672D01*
G01X340136Y-774672D02*
X343050D01*
G01X346693Y-779839D02*
X346566Y-779755D01*
Y-779589D01*
X346693Y-779505D01*
X346820Y-779589D01*
Y-779755D01*
X346693Y-779839D01*
G01Y-777589D02*
X346566Y-777505D01*
Y-777339D01*
X346693Y-777255D01*
X346820Y-777339D01*
Y-777505D01*
X346693Y-777589D01*
G01X351299Y281339D02*
G02Y273071I0J-4134D01*
G02Y281339I0J4134D01*
G01X336299D02*
G02Y273071I0J-4134D01*
G02Y281339I0J4134D01*
G01X351299Y273071D02*
G03Y281339I0J4134D01*
G03Y273071I0J-4134D01*
G01X336299D02*
G03Y281339I0J4134D01*
G03Y273071I0J-4134D01*
G01X351299Y480354D02*
G02Y474055I0J-3149D01*
G02Y480354I0J3149D01*
G01Y474055D02*
G03Y480354I0J3149D01*
G03Y474055I0J-3149D01*
G01X381299Y480354D02*
G02Y474055I0J-3149D01*
G02Y480354I0J3149D01*
G01Y474055D02*
G03Y480354I0J3149D01*
G03Y474055I0J-3149D01*
G01X419093Y-819672D02*
Y-844672D01*
G01X425716Y57073D02*
X500000Y53150D01*
X511811D01*
G02Y41339I0J-5905D01*
G01X500000D01*
X425716Y37415D01*
G02Y57073I-519J9829D01*
G01D02*
G03Y37415I-519J-9829D01*
G01X500000Y41339D01*
X511811D01*
G03Y53150I0J5906D01*
G01X500000D01*
X425716Y57073D01*
G01X411299Y281339D02*
G02Y273071I0J-4134D01*
G02Y281339I0J4134D01*
G01Y273071D02*
G03Y281339I0J4134D01*
G03Y273071I0J-4134D01*
G01Y480354D02*
G02Y474055I0J-3149D01*
G02Y480354I0J3149D01*
G01Y474055D02*
G03Y480354I0J3149D01*
G03Y474055I0J-3149D01*
G01X421726Y-822172D02*
Y-827172D01*
X424260D01*
G01X427333Y-822172D02*
X428853D01*
G01X428093D02*
Y-827172D01*
G01X427333D02*
X428853D01*
G01X433700Y-824505D02*
X433953Y-824255D01*
X434143Y-823839D01*
X434270Y-823255D01*
X434143Y-822755D01*
X433890Y-822422D01*
X433446Y-822172D01*
X431736D01*
Y-827172D01*
X433826D01*
X434270Y-826839D01*
X434523Y-826339D01*
X434650Y-825755D01*
X434523Y-825172D01*
X434143Y-824672D01*
X433700Y-824505D01*
X431736D01*
G01X438293Y-827339D02*
X438166Y-827255D01*
Y-827089D01*
X438293Y-827005D01*
X438420Y-827089D01*
Y-827255D01*
X438293Y-827339D01*
G01Y-825089D02*
X438166Y-825005D01*
Y-824839D01*
X438293Y-824755D01*
X438420Y-824839D01*
Y-825005D01*
X438293Y-825089D01*
G01X426299Y281339D02*
G02Y273071I0J-4134D01*
G02Y281339I0J4134D01*
G01Y273071D02*
G03Y281339I0J4134D01*
G03Y273071I0J-4134D01*
G01X470106Y-847839D02*
X470213Y-847714D01*
X470293Y-847505D01*
X470346Y-847214D01*
X470293Y-846964D01*
X470186Y-846797D01*
X470000Y-846672D01*
X469280D01*
Y-849172D01*
X470160D01*
X470346Y-849005D01*
X470453Y-848755D01*
X470506Y-848464D01*
X470453Y-848172D01*
X470293Y-847922D01*
X470106Y-847839D01*
X469280D01*
G01X472573Y-849172D02*
Y-847505D01*
G01Y-847797D02*
X472466Y-847630D01*
X472306Y-847547D01*
X472120Y-847505D01*
X471933Y-847589D01*
X471773Y-847755D01*
X471666Y-848005D01*
X471613Y-848339D01*
X471666Y-848672D01*
X471773Y-848922D01*
X471933Y-849089D01*
X472120Y-849172D01*
X472306Y-849130D01*
X472466Y-849005D01*
X472573Y-848839D01*
G01X473893Y-848880D02*
X474026Y-849047D01*
X474213Y-849172D01*
X474373D01*
X474533Y-849089D01*
X474640Y-848964D01*
X474693Y-848797D01*
X474666Y-848547D01*
X474560Y-848422D01*
X474080Y-848172D01*
X473973Y-847880D01*
X474026Y-847672D01*
X474133Y-847547D01*
X474293Y-847505D01*
X474453Y-847547D01*
X474613Y-847672D01*
G01X476093Y-848047D02*
X476946D01*
X476866Y-847755D01*
X476733Y-847589D01*
X476546Y-847505D01*
X476360Y-847547D01*
X476200Y-847672D01*
X476093Y-847964D01*
X476040Y-848214D01*
Y-848464D01*
X476093Y-848714D01*
X476226Y-848964D01*
X476386Y-849130D01*
X476573Y-849172D01*
X476760Y-849089D01*
X476946Y-848839D01*
G01X478213Y-849172D02*
Y-846672D01*
G01Y-847922D02*
X478346Y-847672D01*
X478506Y-847547D01*
X478666Y-847505D01*
X478906Y-847589D01*
X479066Y-847755D01*
X479173Y-848047D01*
Y-848380D01*
X479120Y-848714D01*
X479013Y-848964D01*
X478826Y-849130D01*
X478666Y-849172D01*
X478506Y-849130D01*
X478346Y-849005D01*
X478213Y-848797D01*
G01X480893Y-849172D02*
X480733Y-849130D01*
X480573Y-848964D01*
X480466Y-848672D01*
X480413Y-848339D01*
X480466Y-848005D01*
X480573Y-847714D01*
X480733Y-847547D01*
X480893Y-847505D01*
X481053Y-847547D01*
X481213Y-847714D01*
X481320Y-848005D01*
X481346Y-848339D01*
X481320Y-848672D01*
X481213Y-848964D01*
X481053Y-849130D01*
X480893Y-849172D01*
G01X483573D02*
Y-847505D01*
G01Y-847797D02*
X483466Y-847630D01*
X483306Y-847547D01*
X483120Y-847505D01*
X482933Y-847589D01*
X482773Y-847755D01*
X482666Y-848005D01*
X482613Y-848339D01*
X482666Y-848672D01*
X482773Y-848922D01*
X482933Y-849089D01*
X483120Y-849172D01*
X483306Y-849130D01*
X483466Y-849005D01*
X483573Y-848839D01*
G01X484920Y-849172D02*
Y-847505D01*
G01Y-847839D02*
X485053Y-847672D01*
X485186Y-847547D01*
X485373Y-847505D01*
X485506Y-847547D01*
X485666Y-847672D01*
G01X487973Y-846672D02*
Y-849172D01*
G01Y-848797D02*
X487866Y-849005D01*
X487706Y-849130D01*
X487520Y-849172D01*
X487306Y-849089D01*
X487146Y-848880D01*
X487040Y-848630D01*
X487013Y-848339D01*
X487040Y-848047D01*
X487146Y-847797D01*
X487306Y-847589D01*
X487520Y-847505D01*
X487706Y-847547D01*
X487840Y-847630D01*
X487973Y-847797D01*
G01X491360Y-849172D02*
Y-846672D01*
X492026D01*
X492240Y-846797D01*
X492373Y-846964D01*
X492426Y-847297D01*
X492373Y-847630D01*
X492213Y-847839D01*
X492026Y-847964D01*
X491360D01*
G01X492026D02*
X492426Y-849172D01*
G01X493693Y-848047D02*
X494546D01*
X494466Y-847755D01*
X494333Y-847589D01*
X494146Y-847505D01*
X493960Y-847547D01*
X493800Y-847672D01*
X493693Y-847964D01*
X493640Y-848214D01*
Y-848464D01*
X493693Y-848714D01*
X493826Y-848964D01*
X493986Y-849130D01*
X494173Y-849172D01*
X494360Y-849089D01*
X494546Y-848839D01*
G01X495813Y-847505D02*
X496293Y-849172D01*
X496773Y-847505D01*
G01X498493Y-849255D02*
X498440Y-849214D01*
Y-849130D01*
X498493Y-849089D01*
X498546Y-849130D01*
Y-849214D01*
X498493Y-849255D01*
G01X500693Y-849172D02*
X500880Y-849130D01*
X501093Y-849005D01*
X501226Y-848797D01*
X501280Y-848505D01*
X501226Y-848214D01*
X501066Y-847964D01*
X500826Y-847839D01*
X500560D01*
X500400Y-847755D01*
X500266Y-847547D01*
X500213Y-847255D01*
X500293Y-846964D01*
X500480Y-846755D01*
X500693Y-846672D01*
X500906Y-846755D01*
X501093Y-846964D01*
X501173Y-847255D01*
X501120Y-847547D01*
X500986Y-847755D01*
X500826Y-847839D01*
X500560D01*
X500320Y-847964D01*
X500160Y-848214D01*
X500106Y-848505D01*
X500160Y-848797D01*
X500293Y-849005D01*
X500506Y-849130D01*
X500693Y-849172D01*
G01X503106Y-847839D02*
X503213Y-847714D01*
X503293Y-847505D01*
X503346Y-847214D01*
X503293Y-846964D01*
X503186Y-846797D01*
X503000Y-846672D01*
X502280D01*
Y-849172D01*
X503160D01*
X503346Y-849005D01*
X503453Y-848755D01*
X503506Y-848464D01*
X503453Y-848172D01*
X503293Y-847922D01*
X503106Y-847839D01*
X502280D01*
G01X465993Y-822172D02*
Y-827172D01*
G01X464536Y-822172D02*
X467450D01*
G01X471093Y-827172D02*
X470713Y-827089D01*
X470333Y-826755D01*
X470080Y-826172D01*
X469953Y-825505D01*
X470080Y-824839D01*
X470333Y-824255D01*
X470713Y-823922D01*
X471093Y-823839D01*
X471473Y-823922D01*
X471853Y-824255D01*
X472106Y-824839D01*
X472170Y-825505D01*
X472106Y-826172D01*
X471853Y-826755D01*
X471473Y-827089D01*
X471093Y-827172D01*
G01X476193D02*
X475813Y-827089D01*
X475433Y-826755D01*
X475180Y-826172D01*
X475053Y-825505D01*
X475180Y-824839D01*
X475433Y-824255D01*
X475813Y-823922D01*
X476193Y-823839D01*
X476573Y-823922D01*
X476953Y-824255D01*
X477206Y-824839D01*
X477270Y-825505D01*
X477206Y-826172D01*
X476953Y-826755D01*
X476573Y-827089D01*
X476193Y-827172D01*
G01X481293D02*
Y-822172D01*
G01X486393Y-827339D02*
X486266Y-827255D01*
Y-827089D01*
X486393Y-827005D01*
X486520Y-827089D01*
Y-827255D01*
X486393Y-827339D01*
G01Y-825089D02*
X486266Y-825005D01*
Y-824839D01*
X486393Y-824755D01*
X486520Y-824839D01*
Y-825005D01*
X486393Y-825089D01*
G01X462093Y-819672D02*
Y-844672D01*
G01Y-794672D02*
Y-819672D01*
G01X464726Y-802172D02*
Y-797172D01*
X466310D01*
X466816Y-797422D01*
X467133Y-797755D01*
X467260Y-798422D01*
X467133Y-799089D01*
X466753Y-799505D01*
X466310Y-799755D01*
X464726D01*
G01X466310D02*
X467260Y-802172D01*
G01X472360D02*
X469826D01*
Y-797172D01*
X472360D01*
G01X471346Y-799589D02*
X469826D01*
G01X474610Y-797172D02*
X476193Y-802172D01*
X477776Y-797172D01*
G01X481293Y-802339D02*
X481166Y-802255D01*
Y-802089D01*
X481293Y-802005D01*
X481420Y-802089D01*
Y-802255D01*
X481293Y-802339D01*
G01Y-800089D02*
X481166Y-800005D01*
Y-799839D01*
X481293Y-799755D01*
X481420Y-799839D01*
Y-800005D01*
X481293Y-800089D01*
G01X508780Y281339D02*
G02Y273071I0J-4134D01*
G02Y281339I0J4134D01*
G01X493780D02*
G02Y273071I0J-4134D01*
G02Y281339I0J4134D01*
G01X508780Y273071D02*
G03Y281339I0J4134D01*
G03Y273071I0J-4134D01*
G01X493780D02*
G03Y281339I0J4134D01*
G03Y273071I0J-4134D01*
G01X508780Y480354D02*
G02Y474055I0J-3149D01*
G02Y480354I0J3149D01*
G01Y474055D02*
G03Y480354I0J3149D01*
G03Y474055I0J-3149D01*
G01X538780Y480354D02*
G02Y474055I0J-3149D01*
G02Y480354I0J3149D01*
G01Y474055D02*
G03Y480354I0J3149D01*
G03Y474055I0J-3149D01*
G01X568780Y281339D02*
G02Y273071I0J-4134D01*
G02Y281339I0J4134D01*
G01Y273071D02*
G03Y281339I0J4134D01*
G03Y273071I0J-4134D01*
G01Y480354D02*
G02Y474055I0J-3149D01*
G02Y480354I0J3149D01*
G01Y474055D02*
G03Y480354I0J3149D01*
G03Y474055I0J-3149D01*
G01X583780Y281339D02*
G02Y273071I0J-4134D01*
G02Y281339I0J4134D01*
G01Y273071D02*
G03Y281339I0J4134D01*
G03Y273071I0J-4134D01*
G01X651260Y281339D02*
G02Y273071I0J-4134D01*
G02Y281339I0J4134D01*
G01Y273071D02*
G03Y281339I0J4134D01*
G03Y273071I0J-4134D01*
G01X666260Y281339D02*
G02Y273071I0J-4134D01*
G02Y281339I0J4134D01*
G01Y273071D02*
G03Y281339I0J4134D01*
G03Y273071I0J-4134D01*
G01Y480354D02*
G02Y474055I0J-3149D01*
G02Y480354I0J3149D01*
G01Y474055D02*
G03Y480354I0J3149D01*
G03Y474055I0J-3149D01*
G01X696260Y480354D02*
G02Y474055I0J-3149D01*
G02Y480354I0J3149D01*
G01Y474055D02*
G03Y480354I0J3149D01*
G03Y474055I0J-3149D01*
G01X741260Y281339D02*
G02Y273071I0J-4134D01*
G02Y281339I0J4134D01*
G01X726260D02*
G02Y273071I0J-4134D01*
G02Y281339I0J4134D01*
G01X741260Y273071D02*
G03Y281339I0J4134D01*
G03Y273071I0J-4134D01*
G01X726260D02*
G03Y281339I0J4134D01*
G03Y273071I0J-4134D01*
G01Y480354D02*
G02Y474055I0J-3149D01*
G02Y480354I0J3149D01*
G01Y474055D02*
G03Y480354I0J3149D01*
G03Y474055I0J-3149D01*
G01X905512Y41339D02*
X893701D01*
X819417Y37415D01*
G02Y57073I-519J9829D01*
G01X893701Y53150D01*
X905512D01*
G02Y41339I0J-5905D01*
G01Y53150D02*
G02Y41339I0J-5905D01*
G01X893701D01*
X819417Y37415D01*
G02Y57073I-519J9829D01*
G01X893701Y53150D01*
X905512D01*
G01X902488Y237782D02*
X976772Y233858D01*
X988583D01*
G02Y222047I0J-5905D01*
G01X976772D01*
X902488Y218124D01*
G02Y237782I-519J9829D01*
G01D02*
G03Y218124I-519J-9829D01*
G01X976772Y222047D01*
X988583D01*
G03Y233858I0J5906D01*
G01X976772D01*
X902488Y237782D01*
G01X944417Y552309D02*
X1018701Y548386D01*
X1030512D01*
G02Y536575I0J-5905D01*
G01X1018701D01*
X944417Y532651D01*
G02Y552309I-519J9829D01*
G01D02*
G03Y532651I-519J-9829D01*
G01X1018701Y536575D01*
X1030512D01*
G03Y548386I0J5905D01*
G01X1018701D01*
X944417Y552309D01*
G01X1226024Y182736D02*
G02Y166122I0J-8307D01*
G02Y182736I0J8307D01*
G01Y166122D02*
G03Y182736I0J8307D01*
G03Y166122I0J-8307D01*
G01Y407736D02*
G02Y391122I0J-8307D01*
G02Y407736I0J8307D01*
G01Y391122D02*
G03Y407736I0J8307D01*
G03Y391122I0J-8307D01*
G01X1227559Y57480D02*
G02X1252756I12599J0D01*
G02X1227559I-12598J0D01*
G01X1252756D02*
G03X1227559I-12598J0D01*
G03X1252756I12599J0D01*
G01X1227559Y521260D02*
G02X1252756I12599J0D01*
G02X1227559I-12598J0D01*
G01X1252756D02*
G03X1227559I-12598J0D01*
G03X1252756I12599J0D01*
G01X-297025Y-1013390D02*
Y1828909D01*
X3691357D01*
Y-1013390D01*
X-297025D01*
G01X16913Y-817022D02*
X18480D01*
Y-818912D01*
X18010Y-819542D01*
X17461Y-819962D01*
X16678Y-820172D01*
X15895Y-819962D01*
X15346Y-819542D01*
X14876Y-818912D01*
X14563Y-818177D01*
X14406Y-817337D01*
Y-816602D01*
X14563Y-815972D01*
X14876Y-815237D01*
X15346Y-814607D01*
X15816Y-814187D01*
X16443Y-813872D01*
X16991D01*
X17618Y-814082D01*
X18088Y-814502D01*
G01X21020Y-813872D02*
Y-818387D01*
X21333Y-819332D01*
X21960Y-819962D01*
X22743Y-820172D01*
X23526Y-819962D01*
X24153Y-819332D01*
X24466Y-818387D01*
Y-813872D01*
G01X28103D02*
X29983D01*
G01X29043D02*
Y-820172D01*
G01X28103D02*
X29983D01*
G01X33698Y-819332D02*
X34325Y-819857D01*
X35030Y-820172D01*
X35656D01*
X36283Y-819857D01*
X36753Y-819332D01*
X36988Y-818597D01*
X36831Y-817862D01*
X36440Y-817232D01*
X35735Y-816812D01*
X34795Y-816602D01*
X34246Y-816182D01*
X34011Y-815447D01*
X34168Y-814712D01*
X34560Y-814187D01*
X35108Y-813872D01*
X35656D01*
X36205Y-814082D01*
X36675Y-814607D01*
G01X39998Y-820172D02*
Y-813872D01*
G01X43288D02*
Y-820172D01*
G01Y-817022D02*
X39998D01*
G01X45985Y-820172D02*
X47943Y-813872D01*
X49901Y-820172D01*
G01X49196Y-817967D02*
X46690D01*
G01X52441Y-820172D02*
Y-813872D01*
X56045Y-820172D01*
Y-813872D01*
G01X65120Y-820172D02*
Y-813872D01*
X66686D01*
X67313Y-814187D01*
X67783Y-814607D01*
X68175Y-815237D01*
X68488Y-815972D01*
X68566Y-817022D01*
X68488Y-818072D01*
X68175Y-818807D01*
X67783Y-819437D01*
X67313Y-819857D01*
X66686Y-820172D01*
X65120D01*
G01X72203Y-813872D02*
X74083D01*
G01X73143D02*
Y-820172D01*
G01X72203D02*
X74083D01*
G01X77798Y-819332D02*
X78425Y-819857D01*
X79130Y-820172D01*
X79756D01*
X80383Y-819857D01*
X80853Y-819332D01*
X81088Y-818597D01*
X80931Y-817862D01*
X80540Y-817232D01*
X79835Y-816812D01*
X78895Y-816602D01*
X78346Y-816182D01*
X78111Y-815447D01*
X78268Y-814712D01*
X78660Y-814187D01*
X79208Y-813872D01*
X79756D01*
X80305Y-814082D01*
X80775Y-814607D01*
G01X85743Y-813872D02*
Y-820172D01*
G01X83941Y-813872D02*
X87545D01*
G01X92043Y-820382D02*
X91886Y-820277D01*
Y-820067D01*
X92043Y-819962D01*
X92200Y-820067D01*
Y-820277D01*
X92043Y-820382D01*
G01X98186Y-821327D02*
X98500Y-819962D01*
G01X104643Y-813872D02*
Y-820172D01*
G01X102841Y-813872D02*
X106445D01*
G01X108985Y-820172D02*
X110943Y-813872D01*
X112901Y-820172D01*
G01X112196Y-817967D02*
X109690D01*
G01X117243Y-820172D02*
X116616Y-820067D01*
X116068Y-819647D01*
X115598Y-819017D01*
X115285Y-818282D01*
X115128Y-817442D01*
Y-816602D01*
X115285Y-815762D01*
X115598Y-815027D01*
X116068Y-814397D01*
X116616Y-813977D01*
X117243Y-813872D01*
X117870Y-813977D01*
X118418Y-814397D01*
X118888Y-815027D01*
X119201Y-815762D01*
X119358Y-816602D01*
Y-817442D01*
X119201Y-818282D01*
X118888Y-819017D01*
X118418Y-819647D01*
X117870Y-820067D01*
X117243Y-820172D01*
G01X123543D02*
Y-817337D01*
X121976Y-813872D01*
G01X125110D02*
X123543Y-817337D01*
G01X128120Y-813872D02*
Y-818387D01*
X128433Y-819332D01*
X129060Y-819962D01*
X129843Y-820172D01*
X130626Y-819962D01*
X131253Y-819332D01*
X131566Y-818387D01*
Y-813872D01*
G01X134185Y-820172D02*
X136143Y-813872D01*
X138101Y-820172D01*
G01X137396Y-817967D02*
X134890D01*
G01X140641Y-820172D02*
Y-813872D01*
X144245Y-820172D01*
Y-813872D01*
G01X18166Y-824397D02*
X17696Y-824082D01*
X17148Y-823872D01*
X16521D01*
X15816Y-824187D01*
X15268Y-824712D01*
X14876Y-825342D01*
X14563Y-826392D01*
X14485Y-827337D01*
X14641Y-828282D01*
X14876Y-828912D01*
X15346Y-829542D01*
X15895Y-829962D01*
X16443Y-830172D01*
X16991D01*
X17540Y-829962D01*
X18010Y-829647D01*
X18401Y-829227D01*
G01X21803Y-823872D02*
X23683D01*
G01X22743D02*
Y-830172D01*
G01X21803D02*
X23683D01*
G01X29043Y-823872D02*
Y-830172D01*
G01X27241Y-823872D02*
X30845D01*
G01X35343Y-830172D02*
Y-827337D01*
X33776Y-823872D01*
G01X36910D02*
X35343Y-827337D01*
G01X46220Y-828912D02*
X46690Y-829647D01*
X47316Y-830067D01*
X48021Y-830172D01*
X48648Y-830067D01*
X49275Y-829542D01*
X49666Y-828912D01*
X49745Y-828282D01*
X49588Y-827547D01*
X49040Y-827022D01*
X48491Y-826812D01*
X47786D01*
G01X48491D02*
X48961Y-826497D01*
X49353Y-825972D01*
X49510Y-825342D01*
X49353Y-824712D01*
X48961Y-824187D01*
X48256Y-823872D01*
X47551Y-823977D01*
X46846Y-824397D01*
G01X52520Y-828912D02*
X52990Y-829647D01*
X53616Y-830067D01*
X54321Y-830172D01*
X54948Y-830067D01*
X55575Y-829542D01*
X55966Y-828912D01*
X56045Y-828282D01*
X55888Y-827547D01*
X55340Y-827022D01*
X54791Y-826812D01*
X54086D01*
G01X54791D02*
X55261Y-826497D01*
X55653Y-825972D01*
X55810Y-825342D01*
X55653Y-824712D01*
X55261Y-824187D01*
X54556Y-823872D01*
X53851Y-823977D01*
X53146Y-824397D01*
G01X58820Y-828912D02*
X59290Y-829647D01*
X59916Y-830067D01*
X60621Y-830172D01*
X61248Y-830067D01*
X61875Y-829542D01*
X62266Y-828912D01*
X62345Y-828282D01*
X62188Y-827547D01*
X61640Y-827022D01*
X61091Y-826812D01*
X60386D01*
G01X61091D02*
X61561Y-826497D01*
X61953Y-825972D01*
X62110Y-825342D01*
X61953Y-824712D01*
X61561Y-824187D01*
X60856Y-823872D01*
X60151Y-823977D01*
X59446Y-824397D01*
G01X66686Y-830172D02*
X66843Y-828807D01*
X67078Y-827652D01*
X67391Y-826602D01*
X67783Y-825447D01*
X68410Y-823872D01*
X65276D01*
G01X72986Y-830172D02*
X73143Y-828807D01*
X73378Y-827652D01*
X73691Y-826602D01*
X74083Y-825447D01*
X74710Y-823872D01*
X71576D01*
G01X79286Y-831327D02*
X79600Y-829962D01*
G01X85743Y-823872D02*
Y-830172D01*
G01X83941Y-823872D02*
X87545D01*
G01X90085Y-830172D02*
X92043Y-823872D01*
X94001Y-830172D01*
G01X93296Y-827967D02*
X90790D01*
G01X97403Y-823872D02*
X99283D01*
G01X98343D02*
Y-830172D01*
G01X97403D02*
X99283D01*
G01X102293Y-823872D02*
X103390Y-830172D01*
X104643Y-823872D01*
X105896Y-830172D01*
X106993Y-823872D01*
G01X108985Y-830172D02*
X110943Y-823872D01*
X112901Y-830172D01*
G01X112196Y-827967D02*
X109690D01*
G01X115441Y-830172D02*
Y-823872D01*
X119045Y-830172D01*
Y-823872D01*
G01X129451Y-832272D02*
X128668Y-831222D01*
X128276Y-830172D01*
Y-825972D01*
X128668Y-824922D01*
X129451Y-823872D01*
G01X140876Y-830172D02*
Y-823872D01*
X142835D01*
X143461Y-824187D01*
X143853Y-824607D01*
X144010Y-825447D01*
X143853Y-826287D01*
X143383Y-826812D01*
X142835Y-827127D01*
X140876D01*
G01X142835D02*
X144010Y-830172D01*
G01X148743Y-830382D02*
X148586Y-830277D01*
Y-830067D01*
X148743Y-829962D01*
X148900Y-830067D01*
Y-830277D01*
X148743Y-830382D01*
G01X155043Y-830172D02*
X154416Y-830067D01*
X153868Y-829647D01*
X153398Y-829017D01*
X153085Y-828282D01*
X152928Y-827442D01*
Y-826602D01*
X153085Y-825762D01*
X153398Y-825027D01*
X153868Y-824397D01*
X154416Y-823977D01*
X155043Y-823872D01*
X155670Y-823977D01*
X156218Y-824397D01*
X156688Y-825027D01*
X157001Y-825762D01*
X157158Y-826602D01*
Y-827442D01*
X157001Y-828282D01*
X156688Y-829017D01*
X156218Y-829647D01*
X155670Y-830067D01*
X155043Y-830172D01*
G01X161343Y-830382D02*
X161186Y-830277D01*
Y-830067D01*
X161343Y-829962D01*
X161500Y-830067D01*
Y-830277D01*
X161343Y-830382D01*
G01X169366Y-824397D02*
X168896Y-824082D01*
X168348Y-823872D01*
X167721D01*
X167016Y-824187D01*
X166468Y-824712D01*
X166076Y-825342D01*
X165763Y-826392D01*
X165685Y-827337D01*
X165841Y-828282D01*
X166076Y-828912D01*
X166546Y-829542D01*
X167095Y-829962D01*
X167643Y-830172D01*
X168191D01*
X168740Y-829962D01*
X169210Y-829647D01*
X169601Y-829227D01*
G01X173943Y-830382D02*
X173786Y-830277D01*
Y-830067D01*
X173943Y-829962D01*
X174100Y-830067D01*
Y-830277D01*
X173943Y-830382D01*
G01X180635Y-832272D02*
X181418Y-831222D01*
X181810Y-830172D01*
Y-825972D01*
X181418Y-824922D01*
X180635Y-823872D01*
G01X38743Y-799472D02*
X36223Y-799055D01*
X34018Y-797389D01*
X32128Y-794889D01*
X30868Y-791972D01*
X30238Y-788639D01*
Y-785305D01*
X30868Y-781972D01*
X32128Y-779055D01*
X34018Y-776556D01*
X36223Y-774889D01*
X38743Y-774472D01*
X41263Y-774889D01*
X43468Y-776556D01*
X45358Y-779055D01*
X46618Y-781972D01*
X47248Y-785305D01*
Y-788639D01*
X46618Y-791972D01*
X45358Y-794889D01*
X43468Y-797389D01*
X41263Y-799055D01*
X38743Y-799472D01*
G01X41263Y-792805D02*
X45043Y-799472D01*
G01X58588Y-782806D02*
Y-794472D01*
X59848Y-797389D01*
X61738Y-799055D01*
X63943Y-799472D01*
X66148Y-799055D01*
X68038Y-797389D01*
X69298Y-794472D01*
G01Y-799472D02*
Y-782806D01*
G01X94813Y-799472D02*
Y-782806D01*
G01Y-785722D02*
X93553Y-784056D01*
X91663Y-783222D01*
X89458Y-782806D01*
X87253Y-783639D01*
X85363Y-785305D01*
X84103Y-787806D01*
X83473Y-791139D01*
X84103Y-794472D01*
X85363Y-796973D01*
X87253Y-798639D01*
X89458Y-799472D01*
X91663Y-799055D01*
X93553Y-797806D01*
X94813Y-796139D01*
G01X108988Y-799472D02*
Y-782806D01*
G01Y-786972D02*
X110248Y-784889D01*
X112138Y-783222D01*
X114658Y-782806D01*
X116863Y-783222D01*
X118753Y-784889D01*
X119698Y-787806D01*
Y-799472D01*
G01X139543Y-774472D02*
Y-799472D01*
G01X135133Y-782806D02*
X143953D01*
G01X170413Y-799472D02*
Y-782806D01*
G01Y-785722D02*
X169153Y-784056D01*
X167263Y-783222D01*
X165058Y-782806D01*
X162853Y-783639D01*
X160963Y-785305D01*
X159703Y-787806D01*
X159073Y-791139D01*
X159703Y-794472D01*
X160963Y-796973D01*
X162853Y-798639D01*
X165058Y-799472D01*
X167263Y-799055D01*
X169153Y-797806D01*
X170413Y-796139D01*
G01X14641Y-810172D02*
Y-803872D01*
X18245Y-810172D01*
Y-803872D01*
G01X22743Y-810172D02*
X22116Y-810067D01*
X21568Y-809647D01*
X21098Y-809017D01*
X20785Y-808282D01*
X20628Y-807442D01*
Y-806602D01*
X20785Y-805762D01*
X21098Y-805027D01*
X21568Y-804397D01*
X22116Y-803977D01*
X22743Y-803872D01*
X23370Y-803977D01*
X23918Y-804397D01*
X24388Y-805027D01*
X24701Y-805762D01*
X24858Y-806602D01*
Y-807442D01*
X24701Y-808282D01*
X24388Y-809017D01*
X23918Y-809647D01*
X23370Y-810067D01*
X22743Y-810172D01*
G01X29043Y-810382D02*
X28886Y-810277D01*
Y-810067D01*
X29043Y-809962D01*
X29200Y-810067D01*
Y-810277D01*
X29043Y-810382D01*
G01X33855Y-804922D02*
X34325Y-804292D01*
X34873Y-803977D01*
X35500Y-803872D01*
X36283Y-804082D01*
X36831Y-804607D01*
X36988Y-805237D01*
X36910Y-805867D01*
X36596Y-806392D01*
X35030Y-807442D01*
X34325Y-808177D01*
X33855Y-809227D01*
X33698Y-810172D01*
X36988D01*
G01X41643D02*
Y-803872D01*
X40703Y-805132D01*
G01Y-810172D02*
X42583D01*
G01X47943D02*
Y-803872D01*
X47003Y-805132D01*
G01Y-810172D02*
X48883D01*
G01X54086Y-811327D02*
X54400Y-809962D01*
G01X58193Y-803872D02*
X59290Y-810172D01*
X60543Y-803872D01*
X61796Y-810172D01*
X62893Y-803872D01*
G01X68410Y-810172D02*
X65276D01*
Y-803872D01*
X68410D01*
G01X67156Y-806917D02*
X65276D01*
G01X71341Y-810172D02*
Y-803872D01*
X74945Y-810172D01*
Y-803872D01*
G01X77798Y-810172D02*
Y-803872D01*
G01X81088D02*
Y-810172D01*
G01Y-807022D02*
X77798D01*
G01X84020Y-803872D02*
Y-808387D01*
X84333Y-809332D01*
X84960Y-809962D01*
X85743Y-810172D01*
X86526Y-809962D01*
X87153Y-809332D01*
X87466Y-808387D01*
Y-803872D01*
G01X90085Y-810172D02*
X92043Y-803872D01*
X94001Y-810172D01*
G01X93296Y-807967D02*
X90790D01*
G01X103155Y-804922D02*
X103625Y-804292D01*
X104173Y-803977D01*
X104800Y-803872D01*
X105583Y-804082D01*
X106131Y-804607D01*
X106288Y-805237D01*
X106210Y-805867D01*
X105896Y-806392D01*
X104330Y-807442D01*
X103625Y-808177D01*
X103155Y-809227D01*
X102998Y-810172D01*
X106288D01*
G01X109141D02*
Y-803872D01*
X112745Y-810172D01*
Y-803872D01*
G01X115520Y-810172D02*
Y-803872D01*
X117086D01*
X117713Y-804187D01*
X118183Y-804607D01*
X118575Y-805237D01*
X118888Y-805972D01*
X118966Y-807022D01*
X118888Y-808072D01*
X118575Y-808807D01*
X118183Y-809437D01*
X117713Y-809857D01*
X117086Y-810172D01*
X115520D01*
G01X128276D02*
Y-803872D01*
X130235D01*
X130861Y-804187D01*
X131253Y-804607D01*
X131410Y-805447D01*
X131253Y-806287D01*
X130783Y-806812D01*
X130235Y-807127D01*
X128276D01*
G01X130235D02*
X131410Y-810172D01*
G01X134420D02*
Y-803872D01*
X135986D01*
X136613Y-804187D01*
X137083Y-804607D01*
X137475Y-805237D01*
X137788Y-805972D01*
X137866Y-807022D01*
X137788Y-808072D01*
X137475Y-808807D01*
X137083Y-809437D01*
X136613Y-809857D01*
X135986Y-810172D01*
X134420D01*
G01X142443Y-810382D02*
X142286Y-810277D01*
Y-810067D01*
X142443Y-809962D01*
X142600Y-810067D01*
Y-810277D01*
X142443Y-810382D01*
G01X155900Y421400D02*
X124100D01*
Y407600D01*
X155900D01*
Y421400D01*
G01X200950Y100500D02*
G03I-25950J0D01*
G01X150234Y242063D02*
X144234D01*
Y230063D01*
X150234D01*
Y242063D01*
G01X156600Y332600D02*
X150400D01*
Y329400D01*
X156600D01*
Y332600D01*
G01Y337100D02*
X150400D01*
Y333900D01*
X156600D01*
Y337100D01*
G01Y352100D02*
X150400D01*
Y348900D01*
X156600D01*
Y352100D01*
G01Y348100D02*
X150400D01*
Y344900D01*
X156600D01*
Y348100D01*
G01X155317Y422867D02*
Y425967D01*
X154358D01*
X154052Y425812D01*
X153860Y425605D01*
X153783Y425192D01*
X153860Y424779D01*
X154090Y424520D01*
X154358Y424365D01*
X155317D01*
G01X154358D02*
X153783Y422867D01*
G01X152293Y423332D02*
X152063Y423074D01*
X151795Y422919D01*
X151450Y422867D01*
X151105Y422970D01*
X150837Y423177D01*
X150645Y423539D01*
X150607Y423952D01*
X150683Y424365D01*
X150875Y424624D01*
X151143Y424830D01*
X151412Y424882D01*
X151680Y424830D01*
X152025Y424624D01*
X151910Y425967D01*
X150875D01*
G01X148350Y422867D02*
X148082Y422919D01*
X147775Y423074D01*
X147583Y423332D01*
X147507Y423694D01*
X147583Y424055D01*
X147813Y424365D01*
X148158Y424520D01*
X148542D01*
X148772Y424624D01*
X148963Y424882D01*
X149040Y425244D01*
X148925Y425605D01*
X148657Y425864D01*
X148350Y425967D01*
X148043Y425864D01*
X147775Y425605D01*
X147660Y425244D01*
X147737Y424882D01*
X147928Y424624D01*
X148158Y424520D01*
X148542D01*
X148887Y424365D01*
X149117Y424055D01*
X149193Y423694D01*
X149117Y423332D01*
X148925Y423074D01*
X148618Y422919D01*
X148350Y422867D01*
G01X145327D02*
X145250Y423539D01*
X145135Y424107D01*
X144982Y424624D01*
X144790Y425192D01*
X144483Y425967D01*
X146017D01*
G01X142993Y423487D02*
X142763Y423125D01*
X142457Y422919D01*
X142112Y422867D01*
X141805Y422919D01*
X141498Y423177D01*
X141307Y423487D01*
X141268Y423797D01*
X141345Y424159D01*
X141613Y424417D01*
X141882Y424520D01*
X142227D01*
G01X141882D02*
X141652Y424675D01*
X141460Y424934D01*
X141383Y425244D01*
X141460Y425554D01*
X141652Y425812D01*
X141997Y425967D01*
X142342Y425915D01*
X142687Y425709D01*
G01X176804Y226123D02*
X183004D01*
Y229323D01*
X176804D01*
Y226123D01*
G01X182974Y225123D02*
X176774D01*
Y221923D01*
X182974D01*
Y225123D01*
G01X210093Y-779172D02*
Y-787172D01*
X214093D01*
G01X221893D02*
Y-781839D01*
G01Y-782772D02*
X221493Y-782239D01*
X220893Y-781972D01*
X220193Y-781839D01*
X219493Y-782105D01*
X218893Y-782639D01*
X218493Y-783439D01*
X218293Y-784505D01*
X218493Y-785572D01*
X218893Y-786372D01*
X219493Y-786905D01*
X220193Y-787172D01*
X220893Y-787039D01*
X221493Y-786639D01*
X221893Y-786106D01*
G01X225993Y-789572D02*
X226593Y-789839D01*
X227393Y-789572D01*
X227893Y-789039D01*
X228293Y-788372D01*
X228893Y-786239D01*
X230193Y-781839D01*
G01X226993D02*
X228893Y-786239D01*
G01X234593Y-783572D02*
X237793D01*
X237493Y-782639D01*
X236993Y-782105D01*
X236293Y-781839D01*
X235593Y-781972D01*
X234993Y-782372D01*
X234593Y-783305D01*
X234393Y-784106D01*
Y-784905D01*
X234593Y-785705D01*
X235093Y-786505D01*
X235693Y-787039D01*
X236393Y-787172D01*
X237093Y-786905D01*
X237793Y-786106D01*
G01X242693Y-787172D02*
Y-781839D01*
G01Y-782905D02*
X243193Y-782372D01*
X243693Y-781972D01*
X244393Y-781839D01*
X244893Y-781972D01*
X245493Y-782372D01*
G01X209671Y298900D02*
Y305100D01*
X206471D01*
Y298900D01*
X209671D01*
G01X211400D02*
X217600D01*
Y302100D01*
X211400D01*
Y298900D01*
G01X217600Y311100D02*
X211400D01*
Y307900D01*
X217600D01*
Y311100D01*
G01X211400Y303400D02*
X217600D01*
Y306600D01*
X211400D01*
Y303400D01*
G01X229193Y-829172D02*
X232993D01*
X229193Y-837172D01*
X232993D01*
G01X239093Y-831839D02*
Y-837172D01*
G01Y-829705D02*
X238893Y-829572D01*
Y-829305D01*
X239093Y-829172D01*
X239293Y-829305D01*
Y-829572D01*
X239093Y-829705D01*
G01X245793Y-834505D02*
X248393D01*
G01X253093Y-837172D02*
Y-829172D01*
X255493D01*
X256293Y-829572D01*
X256893Y-830505D01*
X257093Y-831572D01*
X256893Y-832639D01*
X256393Y-833439D01*
X255493Y-833839D01*
X253093D01*
G01X263093Y-831839D02*
Y-837172D01*
G01Y-829705D02*
X262893Y-829572D01*
Y-829305D01*
X263093Y-829172D01*
X263293Y-829305D01*
Y-829572D01*
X263093Y-829705D01*
G01X269393Y-837172D02*
Y-831839D01*
G01Y-833172D02*
X269793Y-832505D01*
X270393Y-831972D01*
X271193Y-831839D01*
X271893Y-831972D01*
X272493Y-832505D01*
X272793Y-833439D01*
Y-837172D01*
G01X277693Y-839172D02*
X278393Y-839705D01*
X279193Y-839839D01*
X279893Y-839705D01*
X280493Y-839039D01*
X280893Y-838105D01*
Y-831839D01*
G01Y-832905D02*
X280493Y-832372D01*
X279893Y-831972D01*
X279193Y-831839D01*
X278393Y-832105D01*
X277893Y-832639D01*
X277493Y-833572D01*
X277293Y-834505D01*
X277393Y-835305D01*
X277793Y-836239D01*
X278393Y-836905D01*
X279193Y-837172D01*
X279793Y-837039D01*
X280493Y-836505D01*
X280893Y-835972D01*
G01X221493Y-811106D02*
X222293Y-811772D01*
X223193Y-812172D01*
X223993D01*
X224793Y-811772D01*
X225393Y-811106D01*
X225693Y-810172D01*
X225493Y-809239D01*
X224993Y-808439D01*
X224093Y-807905D01*
X222893Y-807639D01*
X222193Y-807105D01*
X221893Y-806172D01*
X222093Y-805239D01*
X222593Y-804572D01*
X223293Y-804172D01*
X223993D01*
X224693Y-804439D01*
X225293Y-805105D01*
G01X230393Y-804172D02*
X232793D01*
G01X231593D02*
Y-812172D01*
G01X230393D02*
X232793D01*
G01X237593Y-804172D02*
Y-812172D01*
X241593D01*
G01X245393D02*
Y-804172D01*
G01X249193D02*
X245393Y-809106D01*
G01X249793Y-812172D02*
X247093Y-806839D01*
G01X254293Y-809505D02*
X256893D01*
G01X264393Y-807905D02*
X264793Y-807505D01*
X265093Y-806839D01*
X265293Y-805905D01*
X265093Y-805105D01*
X264693Y-804572D01*
X263993Y-804172D01*
X261293D01*
Y-812172D01*
X264593D01*
X265293Y-811639D01*
X265693Y-810839D01*
X265893Y-809905D01*
X265693Y-808972D01*
X265093Y-808172D01*
X264393Y-807905D01*
X261293D01*
G01X271593Y-812172D02*
X270793Y-812039D01*
X270093Y-811505D01*
X269493Y-810705D01*
X269093Y-809772D01*
X268893Y-808705D01*
Y-807639D01*
X269093Y-806572D01*
X269493Y-805639D01*
X270093Y-804839D01*
X270793Y-804305D01*
X271593Y-804172D01*
X272393Y-804305D01*
X273093Y-804839D01*
X273693Y-805639D01*
X274093Y-806572D01*
X274293Y-807639D01*
Y-808705D01*
X274093Y-809772D01*
X273693Y-810705D01*
X273093Y-811505D01*
X272393Y-812039D01*
X271593Y-812172D01*
G01X279593Y-804172D02*
Y-812172D01*
G01X277293Y-804172D02*
X281893D01*
G01X226457Y104173D02*
Y185197D01*
X552047D01*
Y104173D01*
X226457D01*
G01X219900Y298900D02*
X226100D01*
Y302100D01*
X219900D01*
Y298900D01*
G01X228900D02*
X235100D01*
Y302100D01*
X228900D01*
Y298900D01*
G01X226100Y311100D02*
X219900D01*
Y307900D01*
X226100D01*
Y311100D01*
G01X235100D02*
X228900D01*
Y307900D01*
X235100D01*
Y311100D01*
G01X241167Y298900D02*
Y305100D01*
X237967D01*
Y298900D01*
X241167D01*
G01X219900Y303400D02*
X226100D01*
Y306600D01*
X219900D01*
Y303400D01*
G01X228900D02*
X235100D01*
Y306600D01*
X228900D01*
Y303400D01*
G01X225419Y453900D02*
Y460100D01*
X222219D01*
Y453900D01*
X225419D01*
G01X222219Y452100D02*
Y445900D01*
X225419D01*
Y452100D01*
X222219D01*
G01X253100Y298900D02*
Y305100D01*
X249900D01*
Y298900D01*
X253100D01*
G01X249041D02*
Y305100D01*
X245841D01*
Y298900D01*
X249041D01*
G01X336693Y-830505D02*
X337293Y-829705D01*
X337993Y-829305D01*
X338793Y-829172D01*
X339793Y-829439D01*
X340493Y-830105D01*
X340693Y-830905D01*
X340593Y-831706D01*
X340193Y-832372D01*
X338193Y-833705D01*
X337293Y-834639D01*
X336693Y-835972D01*
X336493Y-837172D01*
X340693D01*
G01X346593Y-829172D02*
X345793Y-829439D01*
X345193Y-830105D01*
X344793Y-830905D01*
X344493Y-831972D01*
X344393Y-833172D01*
X344493Y-834372D01*
X344793Y-835439D01*
X345193Y-836239D01*
X345793Y-836905D01*
X346593Y-837172D01*
X347393Y-836905D01*
X347993Y-836239D01*
X348393Y-835439D01*
X348693Y-834372D01*
X348793Y-833172D01*
X348693Y-831972D01*
X348393Y-830905D01*
X347993Y-830105D01*
X347393Y-829439D01*
X346593Y-829172D01*
G01X352693Y-830505D02*
X353293Y-829705D01*
X353993Y-829305D01*
X354793Y-829172D01*
X355793Y-829439D01*
X356493Y-830105D01*
X356693Y-830905D01*
X356593Y-831706D01*
X356193Y-832372D01*
X354193Y-833705D01*
X353293Y-834639D01*
X352693Y-835972D01*
X352493Y-837172D01*
X356693D01*
G01X360693Y-830505D02*
X361293Y-829705D01*
X361993Y-829305D01*
X362793Y-829172D01*
X363793Y-829439D01*
X364493Y-830105D01*
X364693Y-830905D01*
X364593Y-831706D01*
X364193Y-832372D01*
X362193Y-833705D01*
X361293Y-834639D01*
X360693Y-835972D01*
X360493Y-837172D01*
X364693D01*
G01X368793Y-837439D02*
X372393Y-829172D01*
G01X378593Y-837172D02*
Y-829172D01*
X377393Y-830772D01*
G01Y-837172D02*
X379793D01*
G01X384693Y-830505D02*
X385293Y-829705D01*
X385993Y-829305D01*
X386793Y-829172D01*
X387793Y-829439D01*
X388493Y-830105D01*
X388693Y-830905D01*
X388593Y-831706D01*
X388193Y-832372D01*
X386193Y-833705D01*
X385293Y-834639D01*
X384693Y-835972D01*
X384493Y-837172D01*
X388693D01*
G01X392793Y-837439D02*
X396393Y-829172D01*
G01X402593D02*
X401793Y-829439D01*
X401193Y-830105D01*
X400793Y-830905D01*
X400493Y-831972D01*
X400393Y-833172D01*
X400493Y-834372D01*
X400793Y-835439D01*
X401193Y-836239D01*
X401793Y-836905D01*
X402593Y-837172D01*
X403393Y-836905D01*
X403993Y-836239D01*
X404393Y-835439D01*
X404693Y-834372D01*
X404793Y-833172D01*
X404693Y-831972D01*
X404393Y-830905D01*
X403993Y-830105D01*
X403393Y-829439D01*
X402593Y-829172D01*
G01X408693Y-830505D02*
X409293Y-829705D01*
X409993Y-829305D01*
X410793Y-829172D01*
X411793Y-829439D01*
X412493Y-830105D01*
X412693Y-830905D01*
X412593Y-831706D01*
X412193Y-832372D01*
X410193Y-833705D01*
X409293Y-834639D01*
X408693Y-835972D01*
X408493Y-837172D01*
X412693D01*
G01X336393Y-814672D02*
Y-806672D01*
X338393D01*
X339193Y-807072D01*
X339793Y-807605D01*
X340293Y-808405D01*
X340693Y-809339D01*
X340793Y-810672D01*
X340693Y-812005D01*
X340293Y-812939D01*
X339793Y-813739D01*
X339193Y-814272D01*
X338393Y-814672D01*
X336393D01*
G01X344093D02*
X346593Y-806672D01*
X349093Y-814672D01*
G01X348193Y-811872D02*
X344993D01*
G01X354593Y-806672D02*
X353793Y-806939D01*
X353193Y-807605D01*
X352793Y-808405D01*
X352493Y-809472D01*
X352393Y-810672D01*
X352493Y-811872D01*
X352793Y-812939D01*
X353193Y-813739D01*
X353793Y-814405D01*
X354593Y-814672D01*
X355393Y-814405D01*
X355993Y-813739D01*
X356393Y-812939D01*
X356693Y-811872D01*
X356793Y-810672D01*
X356693Y-809472D01*
X356393Y-808405D01*
X355993Y-807605D01*
X355393Y-806939D01*
X354593Y-806672D01*
G01X360693Y-814672D02*
Y-806672D01*
X364493D01*
G01X363093Y-810539D02*
X360693D01*
G01X370593Y-806672D02*
X369793Y-806939D01*
X369193Y-807605D01*
X368793Y-808405D01*
X368493Y-809472D01*
X368393Y-810672D01*
X368493Y-811872D01*
X368793Y-812939D01*
X369193Y-813739D01*
X369793Y-814405D01*
X370593Y-814672D01*
X371393Y-814405D01*
X371993Y-813739D01*
X372393Y-812939D01*
X372693Y-811872D01*
X372793Y-810672D01*
X372693Y-809472D01*
X372393Y-808405D01*
X371993Y-807605D01*
X371393Y-806939D01*
X370593Y-806672D01*
G01X378593D02*
Y-814672D01*
G01X376293Y-806672D02*
X380893D01*
G01X384593Y-814672D02*
Y-806672D01*
X386993D01*
X387793Y-807072D01*
X388393Y-808005D01*
X388593Y-809072D01*
X388393Y-810139D01*
X387893Y-810939D01*
X386993Y-811339D01*
X384593D01*
G01X395393Y-810405D02*
X395793Y-810005D01*
X396093Y-809339D01*
X396293Y-808405D01*
X396093Y-807605D01*
X395693Y-807072D01*
X394993Y-806672D01*
X392293D01*
Y-814672D01*
X395593D01*
X396293Y-814139D01*
X396693Y-813339D01*
X396893Y-812405D01*
X396693Y-811472D01*
X396093Y-810672D01*
X395393Y-810405D01*
X392293D01*
G01X400093Y-814672D02*
X402593Y-806672D01*
X405093Y-814672D01*
G01X404193Y-811872D02*
X400993D01*
G01X408693Y-814672D02*
Y-806672D01*
X412493D01*
G01X411093Y-810539D02*
X408693D01*
G01X418593Y-806672D02*
X417793Y-806939D01*
X417193Y-807605D01*
X416793Y-808405D01*
X416493Y-809472D01*
X416393Y-810672D01*
X416493Y-811872D01*
X416793Y-812939D01*
X417193Y-813739D01*
X417793Y-814405D01*
X418593Y-814672D01*
X419393Y-814405D01*
X419993Y-813739D01*
X420393Y-812939D01*
X420693Y-811872D01*
X420793Y-810672D01*
X420693Y-809472D01*
X420393Y-808405D01*
X419993Y-807605D01*
X419393Y-806939D01*
X418593Y-806672D01*
G01X356693Y-787172D02*
Y-779172D01*
X360493D01*
G01X359093Y-783039D02*
X356693D01*
G01X366593Y-779172D02*
X365793Y-779439D01*
X365193Y-780105D01*
X364793Y-780905D01*
X364493Y-781972D01*
X364393Y-783172D01*
X364493Y-784372D01*
X364793Y-785439D01*
X365193Y-786239D01*
X365793Y-786905D01*
X366593Y-787172D01*
X367393Y-786905D01*
X367993Y-786239D01*
X368393Y-785439D01*
X368693Y-784372D01*
X368793Y-783172D01*
X368693Y-781972D01*
X368393Y-780905D01*
X367993Y-780105D01*
X367393Y-779439D01*
X366593Y-779172D01*
G01X374593D02*
Y-787172D01*
G01X372293Y-779172D02*
X376893D01*
G01X379593Y-789839D02*
X385593D01*
G01X388593Y-787172D02*
Y-779172D01*
X390993D01*
X391793Y-779572D01*
X392393Y-780505D01*
X392593Y-781572D01*
X392393Y-782639D01*
X391893Y-783439D01*
X390993Y-783839D01*
X388593D01*
G01X396393Y-787172D02*
Y-779172D01*
X398393D01*
X399193Y-779572D01*
X399793Y-780105D01*
X400293Y-780905D01*
X400693Y-781839D01*
X400793Y-783172D01*
X400693Y-784505D01*
X400293Y-785439D01*
X399793Y-786239D01*
X399193Y-786772D01*
X398393Y-787172D01*
X396393D01*
G01X407393Y-782905D02*
X407793Y-782505D01*
X408093Y-781839D01*
X408293Y-780905D01*
X408093Y-780105D01*
X407693Y-779572D01*
X406993Y-779172D01*
X404293D01*
Y-787172D01*
X407593D01*
X408293Y-786639D01*
X408693Y-785839D01*
X408893Y-784905D01*
X408693Y-783972D01*
X408093Y-783172D01*
X407393Y-782905D01*
X404293D01*
G01X411593Y-789839D02*
X417593D01*
G01X424793Y-779839D02*
X424193Y-779439D01*
X423493Y-779172D01*
X422693D01*
X421793Y-779572D01*
X421093Y-780239D01*
X420593Y-781039D01*
X420193Y-782372D01*
X420093Y-783572D01*
X420293Y-784772D01*
X420593Y-785572D01*
X421193Y-786372D01*
X421893Y-786905D01*
X422593Y-787172D01*
X423293D01*
X423993Y-786905D01*
X424593Y-786505D01*
X425093Y-785972D01*
G01X430593Y-787172D02*
X429793Y-787039D01*
X429093Y-786505D01*
X428493Y-785705D01*
X428093Y-784772D01*
X427893Y-783705D01*
Y-782639D01*
X428093Y-781572D01*
X428493Y-780639D01*
X429093Y-779839D01*
X429793Y-779305D01*
X430593Y-779172D01*
X431393Y-779305D01*
X432093Y-779839D01*
X432693Y-780639D01*
X433093Y-781572D01*
X433293Y-782639D01*
Y-783705D01*
X433093Y-784772D01*
X432693Y-785705D01*
X432093Y-786505D01*
X431393Y-787039D01*
X430593Y-787172D01*
G01X436293D02*
Y-779172D01*
X440893Y-787172D01*
Y-779172D01*
G01X444093D02*
X446593Y-787172D01*
X449093Y-779172D01*
G01X456593Y-787172D02*
X452593D01*
Y-779172D01*
X456593D01*
G01X454993Y-783039D02*
X452593D01*
G01X460593Y-787172D02*
Y-779172D01*
X463093D01*
X463893Y-779572D01*
X464393Y-780105D01*
X464593Y-781172D01*
X464393Y-782239D01*
X463793Y-782905D01*
X463093Y-783305D01*
X460593D01*
G01X463093D02*
X464593Y-787172D01*
G01X470593Y-779172D02*
Y-787172D01*
G01X468293Y-779172D02*
X472893D01*
G01X480593Y-787172D02*
X476593D01*
Y-779172D01*
X480593D01*
G01X478993Y-783039D02*
X476593D01*
G01X484593Y-787172D02*
Y-779172D01*
X487093D01*
X487893Y-779572D01*
X488393Y-780105D01*
X488593Y-781172D01*
X488393Y-782239D01*
X487793Y-782905D01*
X487093Y-783305D01*
X484593D01*
G01X487093D02*
X488593Y-787172D01*
G01X420969Y176035D02*
Y183535D01*
X418729D01*
X417982Y183160D01*
X417422Y182285D01*
X417235Y181285D01*
X417422Y180285D01*
X417889Y179535D01*
X418729Y179160D01*
X420969D01*
G01X413469Y176035D02*
Y183535D01*
X411135D01*
X410389Y183160D01*
X409922Y182660D01*
X409735Y181660D01*
X409922Y180660D01*
X410482Y180035D01*
X411135Y179660D01*
X413469D01*
G01X411135D02*
X409735Y176035D01*
G01X402235D02*
X405969D01*
Y183535D01*
X402235D01*
G01X403729Y179910D02*
X405969D01*
G01X398562Y177035D02*
X397815Y176410D01*
X396975Y176035D01*
X396229D01*
X395482Y176410D01*
X394922Y177035D01*
X394642Y177910D01*
X394829Y178785D01*
X395295Y179535D01*
X396135Y180035D01*
X397255Y180285D01*
X397909Y180785D01*
X398189Y181660D01*
X398002Y182535D01*
X397535Y183160D01*
X396882Y183535D01*
X396229D01*
X395575Y183285D01*
X395015Y182660D01*
G01X391062Y177035D02*
X390315Y176410D01*
X389475Y176035D01*
X388729D01*
X387982Y176410D01*
X387422Y177035D01*
X387142Y177910D01*
X387329Y178785D01*
X387795Y179535D01*
X388635Y180035D01*
X389755Y180285D01*
X390409Y180785D01*
X390689Y181660D01*
X390502Y182535D01*
X390035Y183160D01*
X389382Y183535D01*
X388729D01*
X388075Y183285D01*
X387515Y182660D01*
G01X382815Y178535D02*
X380389D01*
G01X375875Y176035D02*
Y183535D01*
X372329D01*
G01X373635Y179910D02*
X375875D01*
G01X367722Y183535D02*
X365482D01*
G01X366602D02*
Y176035D01*
G01X367722D02*
X365482D01*
G01X359102Y183535D02*
Y176035D01*
G01X361249Y183535D02*
X356955D01*
G01X359400Y305100D02*
Y298900D01*
X362600D01*
Y305100D01*
X359400D01*
G01X367151Y298900D02*
Y305100D01*
X363951D01*
Y298900D01*
X367151D01*
G01X385900D02*
X392100D01*
Y302100D01*
X385900D01*
Y298900D01*
G01X368400D02*
X374600D01*
Y302100D01*
X368400D01*
Y298900D01*
G01X376900D02*
X383100D01*
Y302100D01*
X376900D01*
Y298900D01*
G01X392100Y311100D02*
X385900D01*
Y307900D01*
X392100D01*
Y311100D01*
G01X374600D02*
X368400D01*
Y307900D01*
X374600D01*
Y311100D01*
G01X383100D02*
X376900D01*
Y307900D01*
X383100D01*
Y311100D01*
G01X385900Y303400D02*
X392100D01*
Y306600D01*
X385900D01*
Y303400D01*
G01X376900D02*
X383100D01*
Y306600D01*
X376900D01*
Y303400D01*
G01X368400D02*
X374600D01*
Y306600D01*
X368400D01*
Y303400D01*
G01X382899Y453900D02*
Y460100D01*
X379699D01*
Y453900D01*
X382899D01*
G01X379699Y452100D02*
Y445900D01*
X382899D01*
Y452100D01*
X379699D01*
G01X395447Y305100D02*
Y298900D01*
X398647D01*
Y305100D01*
X395447D01*
G01X407400D02*
Y298900D01*
X410600D01*
Y305100D01*
X407400D01*
G01X406421Y298900D02*
Y305100D01*
X403221D01*
Y298900D01*
X406421D01*
G01X420193Y459100D02*
Y456878D01*
X420040Y456413D01*
X419733Y456103D01*
X419350Y456000D01*
X418967Y456103D01*
X418660Y456413D01*
X418507Y456878D01*
Y459100D01*
G01X416978Y458583D02*
X416748Y458893D01*
X416480Y459048D01*
X416173Y459100D01*
X415790Y458997D01*
X415522Y458738D01*
X415445Y458428D01*
X415483Y458118D01*
X415637Y457860D01*
X416403Y457343D01*
X416748Y456982D01*
X416978Y456465D01*
X417055Y456000D01*
X415445D01*
G01X412690D02*
Y459100D01*
X414108Y456878D01*
X412192D01*
G01X416207Y453906D02*
Y442094D01*
X428831D01*
Y453906D01*
X416207D01*
G01X416919Y431900D02*
X423119D01*
Y435100D01*
X416919D01*
Y431900D01*
G01X413619Y445900D02*
Y452100D01*
X410419D01*
Y445900D01*
X413619D01*
G01X425093Y-840172D02*
Y-832172D01*
X423893Y-833772D01*
G01Y-840172D02*
X426293D01*
G01X431193Y-836839D02*
X431893Y-835905D01*
X432493Y-835372D01*
X433293Y-835105D01*
X433993Y-835372D01*
X434493Y-835905D01*
X434893Y-836705D01*
X434993Y-837639D01*
X434893Y-838439D01*
X434493Y-839239D01*
X433893Y-839905D01*
X433193Y-840172D01*
X432393Y-839905D01*
X431693Y-839106D01*
X431293Y-837905D01*
X431193Y-836572D01*
X431393Y-834839D01*
X431693Y-833905D01*
X432193Y-832972D01*
X432893Y-832305D01*
X433593Y-832172D01*
X434293Y-832439D01*
X434793Y-833105D01*
G01X441093Y-840439D02*
X440893Y-840305D01*
Y-840039D01*
X441093Y-839905D01*
X441293Y-840039D01*
Y-840305D01*
X441093Y-840439D01*
G01X447193Y-836839D02*
X447893Y-835905D01*
X448493Y-835372D01*
X449293Y-835105D01*
X449993Y-835372D01*
X450493Y-835905D01*
X450893Y-836705D01*
X450993Y-837639D01*
X450893Y-838439D01*
X450493Y-839239D01*
X449893Y-839905D01*
X449193Y-840172D01*
X448393Y-839905D01*
X447693Y-839106D01*
X447293Y-837905D01*
X447193Y-836572D01*
X447393Y-834839D01*
X447693Y-833905D01*
X448193Y-832972D01*
X448893Y-832305D01*
X449593Y-832172D01*
X450293Y-832439D01*
X450793Y-833105D01*
G01X428619Y459100D02*
X422419D01*
Y455900D01*
X428619D01*
Y459100D01*
G01X433619Y452900D02*
Y459100D01*
X430419D01*
Y452900D01*
X433619D01*
G01X470093Y-840172D02*
Y-832172D01*
X468893Y-833772D01*
G01Y-840172D02*
X471293D01*
G01X477893D02*
X478093Y-838439D01*
X478393Y-836972D01*
X478793Y-835639D01*
X479293Y-834172D01*
X480093Y-832172D01*
X476093D01*
G01X486093Y-840439D02*
X485893Y-840305D01*
Y-840039D01*
X486093Y-839905D01*
X486293Y-840039D01*
Y-840305D01*
X486093Y-840439D01*
G01X492193Y-833505D02*
X492793Y-832705D01*
X493493Y-832305D01*
X494293Y-832172D01*
X495293Y-832439D01*
X495993Y-833105D01*
X496193Y-833905D01*
X496093Y-834706D01*
X495693Y-835372D01*
X493693Y-836705D01*
X492793Y-837639D01*
X492193Y-838972D01*
X491993Y-840172D01*
X496193D01*
G01X490193Y-815172D02*
Y-807172D01*
X493993D01*
G01X492593Y-811039D02*
X490193D01*
G01X524632Y298900D02*
Y305100D01*
X521432D01*
Y298900D01*
X524632D01*
G01X526400D02*
X532600D01*
Y302100D01*
X526400D01*
Y298900D01*
G01X535400D02*
X541600D01*
Y302100D01*
X535400D01*
Y298900D01*
G01Y303900D02*
X541600D01*
Y307100D01*
X535400D01*
Y303900D01*
G01X526400D02*
X532600D01*
Y307100D01*
X526400D01*
Y303900D01*
G01X541600Y312100D02*
X535400D01*
Y308900D01*
X541600D01*
Y312100D01*
G01X532600D02*
X526400D01*
Y308900D01*
X532600D01*
Y312100D01*
G01X540380Y453900D02*
Y460100D01*
X537180D01*
Y453900D01*
X540380D01*
G01X537180Y452100D02*
Y445900D01*
X540380D01*
Y452100D01*
X537180D01*
G01X552928Y305100D02*
Y298900D01*
X556128D01*
Y305100D01*
X552928D01*
G01X544400Y298900D02*
X550600D01*
Y302100D01*
X544400D01*
Y298900D01*
G01Y303900D02*
X550600D01*
Y307100D01*
X544400D01*
Y303900D01*
G01X564002Y298900D02*
Y305100D01*
X560802D01*
Y298900D01*
X564002D01*
G01X550600Y312100D02*
X544400D01*
Y308900D01*
X550600D01*
Y312100D01*
G01X571100Y445900D02*
Y452100D01*
X567900D01*
Y445900D01*
X571100D01*
G01X547900Y452100D02*
Y445900D01*
X551100D01*
Y452100D01*
X547900D01*
G01X559700Y443000D02*
X566300D01*
Y456000D01*
X559700D01*
Y443000D01*
G01X590193Y459600D02*
Y457378D01*
X590040Y456913D01*
X589733Y456603D01*
X589350Y456500D01*
X588967Y456603D01*
X588660Y456913D01*
X588507Y457378D01*
Y459600D01*
G01X586978Y459083D02*
X586748Y459393D01*
X586480Y459548D01*
X586173Y459600D01*
X585790Y459497D01*
X585522Y459238D01*
X585445Y458928D01*
X585483Y458618D01*
X585637Y458360D01*
X586403Y457843D01*
X586748Y457482D01*
X586978Y456965D01*
X587055Y456500D01*
X585445D01*
G01X583993Y457120D02*
X583763Y456758D01*
X583457Y456552D01*
X583112Y456500D01*
X582805Y456552D01*
X582498Y456810D01*
X582307Y457120D01*
X582268Y457430D01*
X582345Y457792D01*
X582613Y458050D01*
X582882Y458153D01*
X583227D01*
G01X582882D02*
X582652Y458308D01*
X582460Y458567D01*
X582383Y458877D01*
X582460Y459187D01*
X582652Y459445D01*
X582997Y459600D01*
X583342Y459548D01*
X583687Y459342D01*
G01X573688Y453906D02*
Y442094D01*
X586312D01*
Y453906D01*
X573688D01*
G01X574400Y431900D02*
X580600D01*
Y435100D01*
X574400D01*
Y431900D01*
G01X580100Y459100D02*
X573900D01*
Y455900D01*
X580100D01*
Y459100D01*
G01X591100Y447400D02*
Y453600D01*
X587900D01*
Y447400D01*
X591100D01*
G01X1002854Y174880D02*
Y93857D01*
X642264D01*
Y174880D01*
X1002854D01*
G01X682113Y298900D02*
Y305100D01*
X678913D01*
Y298900D01*
X682113D01*
G01X683881D02*
X690081D01*
Y302100D01*
X683881D01*
Y298900D01*
G01Y303900D02*
X690081D01*
Y307100D01*
X683881D01*
Y303900D01*
G01X690081Y312100D02*
X683881D01*
Y308900D01*
X690081D01*
Y312100D01*
G01X692881Y298900D02*
X699081D01*
Y302100D01*
X692881D01*
Y298900D01*
G01X701881D02*
X708081D01*
Y302100D01*
X701881D01*
Y298900D01*
G01X710409Y305100D02*
Y298900D01*
X713609D01*
Y305100D01*
X710409D01*
G01X692881Y303900D02*
X699081D01*
Y307100D01*
X692881D01*
Y303900D01*
G01X701881D02*
X708081D01*
Y307100D01*
X701881D01*
Y303900D01*
G01X699081Y312100D02*
X692881D01*
Y308900D01*
X699081D01*
Y312100D01*
G01X708081D02*
X701881D01*
Y308900D01*
X708081D01*
Y312100D01*
G01X697861Y453900D02*
Y460100D01*
X694661D01*
Y453900D01*
X697861D01*
G01X694661Y452100D02*
Y445900D01*
X697861D01*
Y452100D01*
X694661D01*
G01X725600Y298900D02*
Y305100D01*
X722400D01*
Y298900D01*
X725600D01*
G01X721483D02*
Y305100D01*
X718283D01*
Y298900D01*
X721483D01*
G01X749600Y340100D02*
X743400D01*
Y336900D01*
X749600D01*
Y340100D01*
G01Y336100D02*
X743400D01*
Y332900D01*
X749600D01*
Y336100D01*
G01Y326100D02*
X743400D01*
Y322900D01*
X749600D01*
Y326100D01*
G01Y330100D02*
X743400D01*
Y326900D01*
X749600D01*
Y330100D01*
G01X736600Y340100D02*
X730400D01*
Y336900D01*
X736600D01*
Y340100D01*
G01Y330100D02*
X730400D01*
Y326900D01*
X736600D01*
Y330100D01*
G01X749600Y344100D02*
X743400D01*
Y340900D01*
X749600D01*
Y344100D01*
G01Y349300D02*
X743400D01*
Y346100D01*
X749600D01*
Y349300D01*
G01Y354800D02*
X743400D01*
Y351600D01*
X749600D01*
Y354800D01*
G01Y363100D02*
X743400D01*
Y359900D01*
X749600D01*
Y363100D01*
G01X772204Y622574D02*
Y648800D01*
X737628Y635687D01*
X772204Y622574D01*
G01X840067Y98000D02*
Y105500D01*
X837827D01*
X837080Y105125D01*
X836520Y104250D01*
X836333Y103250D01*
X836520Y102250D01*
X836987Y101500D01*
X837827Y101125D01*
X840067D01*
G01X832567Y98000D02*
Y105500D01*
X830233D01*
X829487Y105125D01*
X829020Y104625D01*
X828833Y103625D01*
X829020Y102625D01*
X829580Y102000D01*
X830233Y101625D01*
X832567D01*
G01X830233D02*
X828833Y98000D01*
G01X821333D02*
X825067D01*
Y105500D01*
X821333D01*
G01X822827Y101875D02*
X825067D01*
G01X817660Y99000D02*
X816913Y98375D01*
X816073Y98000D01*
X815327D01*
X814580Y98375D01*
X814020Y99000D01*
X813740Y99875D01*
X813927Y100750D01*
X814393Y101500D01*
X815233Y102000D01*
X816353Y102250D01*
X817007Y102750D01*
X817287Y103625D01*
X817100Y104500D01*
X816633Y105125D01*
X815980Y105500D01*
X815327D01*
X814673Y105250D01*
X814113Y104625D01*
G01X810160Y99000D02*
X809413Y98375D01*
X808573Y98000D01*
X807827D01*
X807080Y98375D01*
X806520Y99000D01*
X806240Y99875D01*
X806427Y100750D01*
X806893Y101500D01*
X807733Y102000D01*
X808853Y102250D01*
X809507Y102750D01*
X809787Y103625D01*
X809600Y104500D01*
X809133Y105125D01*
X808480Y105500D01*
X807827D01*
X807173Y105250D01*
X806613Y104625D01*
G01X801913Y100500D02*
X799487D01*
G01X794973Y98000D02*
Y105500D01*
X791427D01*
G01X792733Y101875D02*
X794973D01*
G01X786820Y105500D02*
X784580D01*
G01X785700D02*
Y98000D01*
G01X786820D02*
X784580D01*
G01X778200Y105500D02*
Y98000D01*
G01X780347Y105500D02*
X776053D01*
G01X771500Y358000D02*
X767508Y360992D01*
X762992D01*
Y335008D01*
X780008D01*
Y360992D01*
X775492D01*
X771500Y358000D01*
G01X780100Y371100D02*
X773900D01*
Y367900D01*
X780100D01*
Y371100D01*
G01X774507Y622270D02*
X774197Y622462D01*
X773990Y622692D01*
X773887Y622960D01*
X773990Y623267D01*
X774197Y623497D01*
X774507Y623727D01*
X774920Y623804D01*
X776987D01*
G01X773887Y626137D02*
X776987D01*
X776367Y625677D01*
G01X773887D02*
Y626597D01*
G01X774507Y628394D02*
X774145Y628624D01*
X773939Y628930D01*
X773887Y629275D01*
X773939Y629582D01*
X774197Y629889D01*
X774507Y630080D01*
X774817Y630119D01*
X775179Y630042D01*
X775437Y629774D01*
X775540Y629505D01*
Y629160D01*
G01Y629505D02*
X775695Y629735D01*
X775954Y629927D01*
X776264Y630004D01*
X776574Y629927D01*
X776832Y629735D01*
X776987Y629390D01*
X776935Y629045D01*
X776729Y628700D01*
G01X808100Y277900D02*
Y284100D01*
X804900D01*
Y277900D01*
X808100D01*
G01X795900Y328400D02*
X802100D01*
Y331600D01*
X795900D01*
Y328400D01*
G01Y333400D02*
X802100D01*
Y336600D01*
X795900D01*
Y333400D01*
G01Y339400D02*
X802100D01*
Y342600D01*
X795900D01*
Y339400D01*
G01Y344900D02*
X802100D01*
Y348100D01*
X795900D01*
Y344900D01*
G01X802100Y358600D02*
X795900D01*
Y355400D01*
X802100D01*
Y358600D01*
G01Y363600D02*
X795900D01*
Y360400D01*
X802100D01*
Y363600D01*
G01X795900Y350400D02*
X802100D01*
Y353600D01*
X795900D01*
Y350400D01*
G01X789693Y368100D02*
Y365878D01*
X789540Y365413D01*
X789233Y365103D01*
X788850Y365000D01*
X788467Y365103D01*
X788160Y365413D01*
X788007Y365878D01*
Y368100D01*
G01X786478Y367583D02*
X786248Y367893D01*
X785980Y368048D01*
X785673Y368100D01*
X785290Y367997D01*
X785022Y367738D01*
X784945Y367428D01*
X784983Y367118D01*
X785137Y366860D01*
X785903Y366343D01*
X786248Y365982D01*
X786478Y365465D01*
X786555Y365000D01*
X784945D01*
G01X783493Y365465D02*
X783263Y365207D01*
X782995Y365052D01*
X782650Y365000D01*
X782305Y365103D01*
X782037Y365310D01*
X781845Y365672D01*
X781807Y366085D01*
X781883Y366498D01*
X782075Y366757D01*
X782343Y366963D01*
X782612Y367015D01*
X782880Y366963D01*
X783225Y366757D01*
X783110Y368100D01*
X782075D01*
G01X824400Y267600D02*
Y261400D01*
X827600D01*
Y267600D01*
X824400D01*
G01X829400D02*
Y261400D01*
X832600D01*
Y267600D01*
X829400D01*
G01X834400D02*
Y261400D01*
X837600D01*
Y267600D01*
X834400D01*
G01X827600Y271400D02*
Y277600D01*
X824400D01*
Y271400D01*
X827600D01*
G01X832600D02*
Y277600D01*
X829400D01*
Y271400D01*
X832600D01*
G01X837600D02*
Y277600D01*
X834400D01*
Y271400D01*
X837600D01*
G01X817600D02*
Y277600D01*
X814400D01*
Y271400D01*
X817600D01*
G01X822600D02*
Y277600D01*
X819400D01*
Y271400D01*
X822600D01*
G01X809400Y277600D02*
Y271400D01*
X812600D01*
Y277600D01*
X809400D01*
G01X817150Y297107D02*
X814928D01*
X814463Y297260D01*
X814153Y297567D01*
X814050Y297950D01*
X814153Y298333D01*
X814463Y298640D01*
X814928Y298793D01*
X817150D01*
G01X814050Y301510D02*
X817150D01*
X814928Y300092D01*
Y302008D01*
G01X818400Y291600D02*
X849600D01*
Y307400D01*
X818400D01*
Y301800D01*
X820700Y299500D01*
X818400Y297200D01*
Y291600D01*
G01X832900Y330900D02*
X839100D01*
Y334100D01*
X832900D01*
Y330900D01*
G01X828600Y335600D02*
X822400D01*
Y332400D01*
X828600D01*
Y335600D01*
G01X809900Y328100D02*
Y321900D01*
X813100D01*
Y328100D01*
X809900D01*
G01X813900D02*
Y321900D01*
X817100D01*
Y328100D01*
X813900D01*
G01X821900D02*
Y321900D01*
X825100D01*
Y328100D01*
X821900D01*
G01X821100Y321900D02*
Y328100D01*
X817900D01*
Y321900D01*
X821100D01*
G01X829100D02*
Y328100D01*
X825900D01*
Y321900D01*
X829100D01*
G01X839100Y325100D02*
X832900D01*
Y321900D01*
X839100D01*
Y325100D01*
G01Y329600D02*
X832900D01*
Y326400D01*
X839100D01*
Y329600D01*
G01X823100Y353400D02*
Y359600D01*
X819900D01*
Y353400D01*
X823100D01*
G01X825400Y359600D02*
Y353400D01*
X828600D01*
Y359600D01*
X825400D01*
G01X806900Y339400D02*
X813100D01*
Y342600D01*
X806900D01*
Y339400D01*
G01Y355400D02*
X813100D01*
Y358600D01*
X806900D01*
Y355400D01*
G01Y360400D02*
X813100D01*
Y363600D01*
X806900D01*
Y360400D01*
G01X830900Y359600D02*
Y353400D01*
X834100D01*
Y359600D01*
X830900D01*
G01X838100Y345807D02*
X835878D01*
X835413Y345960D01*
X835103Y346267D01*
X835000Y346650D01*
X835103Y347033D01*
X835413Y347340D01*
X835878Y347493D01*
X838100D01*
G01X836292Y349022D02*
X836653Y349290D01*
X836860Y349520D01*
X836963Y349827D01*
X836860Y350095D01*
X836653Y350287D01*
X836343Y350440D01*
X835982Y350478D01*
X835672Y350440D01*
X835362Y350287D01*
X835103Y350057D01*
X835000Y349788D01*
X835103Y349482D01*
X835413Y349213D01*
X835878Y349060D01*
X836395Y349022D01*
X837067Y349098D01*
X837428Y349213D01*
X837790Y349405D01*
X838048Y349673D01*
X838100Y349942D01*
X837997Y350210D01*
X837738Y350402D01*
G01X832831Y351512D02*
X824169D01*
Y340488D01*
X832831D01*
G01Y351512D02*
Y340488D01*
G01X854400Y267600D02*
Y261400D01*
X857600D01*
Y267600D01*
X854400D01*
G01X844400D02*
Y261400D01*
X847600D01*
Y267600D01*
X844400D01*
G01X849400D02*
Y261400D01*
X852600D01*
Y267600D01*
X849400D01*
G01X839400D02*
Y261400D01*
X842600D01*
Y267600D01*
X839400D01*
G01X847600Y271400D02*
Y277600D01*
X844400D01*
Y271400D01*
X847600D01*
G01X852600D02*
Y277600D01*
X849400D01*
Y271400D01*
X852600D01*
G01X857600D02*
Y277600D01*
X854400D01*
Y271400D01*
X857600D01*
G01X842600D02*
Y277600D01*
X839400D01*
Y271400D01*
X842600D01*
G01X850400Y335600D02*
Y329400D01*
X853600D01*
Y335600D01*
X850400D01*
G01X848993Y333050D02*
Y330828D01*
X848840Y330363D01*
X848533Y330053D01*
X848150Y329950D01*
X847767Y330053D01*
X847460Y330363D01*
X847307Y330828D01*
Y333050D01*
G01X845050Y329950D02*
X844782Y330002D01*
X844475Y330157D01*
X844283Y330415D01*
X844207Y330777D01*
X844283Y331138D01*
X844513Y331448D01*
X844858Y331603D01*
X845242D01*
X845472Y331707D01*
X845663Y331965D01*
X845740Y332327D01*
X845625Y332688D01*
X845357Y332947D01*
X845050Y333050D01*
X844743Y332947D01*
X844475Y332688D01*
X844360Y332327D01*
X844437Y331965D01*
X844628Y331707D01*
X844858Y331603D01*
X845242D01*
X845587Y331448D01*
X845817Y331138D01*
X845893Y330777D01*
X845817Y330415D01*
X845625Y330157D01*
X845318Y330002D01*
X845050Y329950D01*
G01X854602Y353000D02*
X842398D01*
Y337000D01*
X854602D01*
Y353000D01*
G01X882400Y334100D02*
Y330300D01*
X880600Y328500D01*
X882400Y326700D01*
Y322900D01*
X862600D01*
Y334100D01*
X882400D01*
G01X862300Y367300D02*
X869700D01*
Y384700D01*
X862300D01*
Y367300D01*
G01X843300D02*
X850700D01*
Y384700D01*
X843300D01*
Y367300D01*
G01X852800D02*
X860200D01*
Y384700D01*
X852800D01*
Y367300D01*
G01X866100Y351400D02*
Y357600D01*
X862900D01*
Y351400D01*
X866100D01*
G01X844600Y355400D02*
Y361600D01*
X841400D01*
Y355400D01*
X844600D01*
G01X845900Y361600D02*
Y355400D01*
X849100D01*
Y361600D01*
X845900D01*
G01X851400D02*
Y355400D01*
X854600D01*
Y361600D01*
X851400D01*
G01X857233Y574814D02*
G03X903460Y558620I20277J-16194D01*
G01X889600Y276400D02*
Y282600D01*
X886400D01*
Y276400D01*
X889600D01*
G01X879100D02*
Y282600D01*
X875900D01*
Y276400D01*
X879100D01*
G01X885600D02*
Y282600D01*
X882400D01*
Y276400D01*
X885600D01*
G01X896100D02*
Y282600D01*
X892900D01*
Y276400D01*
X896100D01*
G01X895693Y305600D02*
Y303378D01*
X895540Y302913D01*
X895233Y302603D01*
X894850Y302500D01*
X894467Y302603D01*
X894160Y302913D01*
X894007Y303378D01*
Y305600D01*
G01X892478Y305083D02*
X892248Y305393D01*
X891980Y305548D01*
X891673Y305600D01*
X891290Y305497D01*
X891022Y305238D01*
X890945Y304928D01*
X890983Y304618D01*
X891137Y304360D01*
X891903Y303843D01*
X892248Y303482D01*
X892478Y302965D01*
X892555Y302500D01*
X890945D01*
G01X888727D02*
X888650Y303172D01*
X888535Y303740D01*
X888382Y304257D01*
X888190Y304825D01*
X887883Y305600D01*
X889417D01*
G01X900312Y289094D02*
Y300906D01*
X887688D01*
Y289094D01*
X900312D01*
G01X876600Y305400D02*
Y311600D01*
X873400D01*
Y305400D01*
X876600D01*
G01X881600D02*
Y311600D01*
X878400D01*
Y305400D01*
X881600D01*
G01X876600Y292400D02*
Y298600D01*
X873400D01*
Y292400D01*
X876600D01*
G01X881600D02*
Y298600D01*
X878400D01*
Y292400D01*
X881600D01*
G01X871600Y305400D02*
Y311600D01*
X868400D01*
Y305400D01*
X871600D01*
G01Y292400D02*
Y298600D01*
X868400D01*
Y292400D01*
X871600D01*
G01X886600Y324807D02*
X884378D01*
X883913Y324960D01*
X883603Y325267D01*
X883500Y325650D01*
X883603Y326033D01*
X883913Y326340D01*
X884378Y326493D01*
X886600D01*
G01X883500Y328750D02*
X886600D01*
X885980Y328290D01*
G01X883500D02*
Y329210D01*
G01X886600Y331850D02*
X886497Y331543D01*
X886238Y331313D01*
X885928Y331160D01*
X885515Y331045D01*
X885050Y331007D01*
X884585Y331045D01*
X884172Y331160D01*
X883862Y331313D01*
X883603Y331543D01*
X883500Y331850D01*
X883603Y332157D01*
X883862Y332387D01*
X884172Y332540D01*
X884585Y332655D01*
X885050Y332693D01*
X885515Y332655D01*
X885928Y332540D01*
X886238Y332387D01*
X886497Y332157D01*
X886600Y331850D01*
G01X897100Y341807D02*
X894878D01*
X894413Y341960D01*
X894103Y342267D01*
X894000Y342650D01*
X894103Y343033D01*
X894413Y343340D01*
X894878Y343493D01*
X897100D01*
G01X896583Y345022D02*
X896893Y345252D01*
X897048Y345520D01*
X897100Y345827D01*
X896997Y346210D01*
X896738Y346478D01*
X896428Y346555D01*
X896118Y346517D01*
X895860Y346363D01*
X895343Y345597D01*
X894982Y345252D01*
X894465Y345022D01*
X894000Y344945D01*
Y346555D01*
G01X897100Y348850D02*
X896997Y348543D01*
X896738Y348313D01*
X896428Y348160D01*
X896015Y348045D01*
X895550Y348007D01*
X895085Y348045D01*
X894672Y348160D01*
X894362Y348313D01*
X894103Y348543D01*
X894000Y348850D01*
X894103Y349157D01*
X894362Y349387D01*
X894672Y349540D01*
X895085Y349655D01*
X895550Y349693D01*
X896015Y349655D01*
X896428Y349540D01*
X896738Y349387D01*
X896997Y349157D01*
X897100Y348850D01*
G01X881300Y367300D02*
X888700D01*
Y384700D01*
X881300D01*
Y367300D01*
G01X890800D02*
X898200D01*
Y384700D01*
X890800D01*
Y367300D01*
G01X871800D02*
X879200D01*
Y384700D01*
X871800D01*
Y367300D01*
G01X879600Y351400D02*
Y357600D01*
X876400D01*
Y351400D01*
X879600D01*
G01X872400Y357600D02*
Y351400D01*
X875600D01*
Y357600D01*
X872400D01*
G01X870600Y351400D02*
Y357600D01*
X867400D01*
Y351400D01*
X870600D01*
G01X881400Y357600D02*
Y351400D01*
X884600D01*
Y357600D01*
X881400D01*
G01X900100Y276400D02*
Y282600D01*
X896900D01*
Y276400D01*
X900100D01*
G01X917900Y282600D02*
Y276400D01*
X921100D01*
Y282600D01*
X917900D01*
G01X910600Y276400D02*
Y282600D01*
X907400D01*
Y276400D01*
X910600D01*
G01X906600D02*
Y282600D01*
X903400D01*
Y276400D01*
X906600D01*
G01X917100D02*
Y282600D01*
X913900D01*
Y276400D01*
X917100D01*
G01X902900Y299100D02*
Y292900D01*
X906100D01*
Y299100D01*
X902900D01*
G01X911100Y292900D02*
Y299100D01*
X907900D01*
Y292900D01*
X911100D01*
G01X916100D02*
Y299100D01*
X912900D01*
Y292900D01*
X916100D01*
G01X912831Y318512D02*
X904169D01*
Y307488D01*
X912831D01*
G01Y318512D02*
Y307488D01*
G01X905100Y320900D02*
Y327100D01*
X901900D01*
Y320900D01*
X905100D01*
G01X906400Y327100D02*
Y320900D01*
X909600D01*
Y327100D01*
X906400D01*
G01X911100Y330900D02*
Y337100D01*
X907900D01*
Y330900D01*
X911100D01*
G01X914100Y320900D02*
Y327100D01*
X910900D01*
Y320900D01*
X914100D01*
G01X925100Y327807D02*
X922878D01*
X922413Y327960D01*
X922103Y328267D01*
X922000Y328650D01*
X922103Y329033D01*
X922413Y329340D01*
X922878Y329493D01*
X925100D01*
G01X922362Y331098D02*
X922103Y331367D01*
X922000Y331673D01*
X922103Y331980D01*
X922413Y332248D01*
X922878Y332440D01*
X923343Y332517D01*
X923912D01*
X924377Y332440D01*
X924790Y332248D01*
X924997Y332018D01*
X925100Y331750D01*
X924997Y331443D01*
X924790Y331213D01*
X924480Y331060D01*
X924067Y330983D01*
X923705Y331060D01*
X923343Y331252D01*
X923137Y331482D01*
X923085Y331750D01*
X923188Y332057D01*
X923447Y332287D01*
X923912Y332517D01*
G01X926102Y354000D02*
X913898D01*
Y338000D01*
X926102D01*
Y354000D01*
G01X917600Y313307D02*
X915378D01*
X914913Y313460D01*
X914603Y313767D01*
X914500Y314150D01*
X914603Y314533D01*
X914913Y314840D01*
X915378Y314993D01*
X917600D01*
G01X914965Y316407D02*
X914707Y316637D01*
X914552Y316905D01*
X914500Y317250D01*
X914603Y317595D01*
X914810Y317863D01*
X915172Y318055D01*
X915585Y318093D01*
X915998Y318017D01*
X916257Y317825D01*
X916463Y317557D01*
X916515Y317288D01*
X916463Y317020D01*
X916257Y316675D01*
X917600Y316790D01*
Y317825D01*
G01X911312Y339594D02*
Y351406D01*
X898688D01*
Y339594D01*
X911312D01*
G01X900300Y367300D02*
X907700D01*
Y384700D01*
X900300D01*
Y367300D01*
G01X919800D02*
X927200D01*
Y384700D01*
X919800D01*
Y367300D01*
G01X909800D02*
X917200D01*
Y384700D01*
X909800D01*
Y367300D01*
G01X917100Y356400D02*
Y362600D01*
X913900D01*
Y356400D01*
X917100D01*
G01X921600D02*
Y362600D01*
X918400D01*
Y356400D01*
X921600D01*
G01X922900Y362600D02*
Y356400D01*
X926100D01*
Y362600D01*
X922900D01*
G01X903460Y558620D02*
G03X897582Y575067I-25949J0D01*
G01X990410Y16950D02*
G03I-25950J0D01*
G01X948600Y276400D02*
Y282600D01*
X945400D01*
Y276400D01*
X948600D01*
G01X941600D02*
Y282600D01*
X938400D01*
Y276400D01*
X941600D01*
G01X931400Y282600D02*
Y276400D01*
X934600D01*
Y282600D01*
X931400D01*
G01X924400D02*
Y276400D01*
X927600D01*
Y282600D01*
X924400D01*
G01X935900Y304900D02*
X942100D01*
Y308100D01*
X935900D01*
Y304900D01*
G01X945400Y301600D02*
Y295400D01*
X948600D01*
Y301600D01*
X945400D01*
G01X938400D02*
Y295400D01*
X941600D01*
Y301600D01*
X938400D01*
G01X948600Y286400D02*
Y292600D01*
X945400D01*
Y286400D01*
X948600D01*
G01X941600D02*
Y292600D01*
X938400D01*
Y286400D01*
X941600D01*
G01X934600D02*
Y292600D01*
X931400D01*
Y286400D01*
X934600D01*
G01X936096Y309285D02*
X942296D01*
Y312485D01*
X936096D01*
Y309285D01*
G01X942296Y316985D02*
X936096D01*
Y313785D01*
X942296D01*
Y316985D01*
G01X931596D02*
Y310785D01*
X934796D01*
Y316985D01*
X931596D01*
G01X930100Y329807D02*
X927878D01*
X927413Y329960D01*
X927103Y330267D01*
X927000Y330650D01*
X927103Y331033D01*
X927413Y331340D01*
X927878Y331493D01*
X930100D01*
G01X927000Y333750D02*
X930100D01*
X929480Y333290D01*
G01X927000D02*
Y334210D01*
G01X931196Y325985D02*
X943196D01*
Y336785D01*
X931196D01*
Y333385D01*
X933196Y331385D01*
X931196Y329385D01*
Y325985D01*
G01X929300Y367300D02*
X936700D01*
Y384700D01*
X929300D01*
Y367300D01*
G01X938800D02*
X946200D01*
Y384700D01*
X938800D01*
Y367300D01*
G01X948300D02*
X955700D01*
Y384700D01*
X948300D01*
Y367300D01*
G01X942796Y349485D02*
X936596D01*
Y346285D01*
X942796D01*
Y349485D01*
G01X936596Y350785D02*
X942796D01*
Y353985D01*
X936596D01*
Y350785D01*
G01X939600Y356400D02*
Y362600D01*
X936400D01*
Y356400D01*
X939600D01*
G01X931596Y352485D02*
Y346285D01*
X934796D01*
Y352485D01*
X931596D01*
G01X1012400Y93094D02*
X1009300D01*
X1009920Y93554D01*
G01X1012400D02*
Y92634D01*
G01X1011780Y123837D02*
X1012142Y123607D01*
X1012348Y123301D01*
X1012400Y122956D01*
X1012348Y122649D01*
X1012090Y122342D01*
X1011780Y122151D01*
X1011470Y122112D01*
X1011108Y122189D01*
X1010850Y122457D01*
X1010747Y122726D01*
Y123071D01*
G01Y122726D02*
X1010592Y122496D01*
X1010333Y122304D01*
X1010023Y122227D01*
X1009713Y122304D01*
X1009455Y122496D01*
X1009300Y122841D01*
X1009352Y123186D01*
X1009558Y123531D01*
G01X1036973Y100900D02*
X1039213D01*
G01X1038000Y99275D02*
Y102525D01*
G01X1049043Y89950D02*
Y93050D01*
X1048277D01*
X1047970Y92895D01*
X1047740Y92688D01*
X1047548Y92378D01*
X1047395Y92017D01*
X1047357Y91500D01*
X1047395Y90983D01*
X1047548Y90622D01*
X1047740Y90312D01*
X1047970Y90105D01*
X1048277Y89950D01*
X1049043D01*
G01X1045100D02*
Y93050D01*
X1045560Y92430D01*
G01Y89950D02*
X1044640D01*
G01X1042728Y92533D02*
X1042498Y92843D01*
X1042230Y92998D01*
X1041923Y93050D01*
X1041540Y92947D01*
X1041272Y92688D01*
X1041195Y92378D01*
X1041233Y92068D01*
X1041387Y91810D01*
X1042153Y91293D01*
X1042498Y90932D01*
X1042728Y90415D01*
X1042805Y89950D01*
X1041195D01*
G01X1070173Y106248D02*
X1040614D01*
Y94752D01*
X1070173D01*
Y106248D01*
G01X1040400Y149400D02*
X1046600D01*
Y152600D01*
X1040400D01*
Y149400D01*
G01X1039100Y141100D02*
X1032900D01*
Y137900D01*
X1039100D01*
Y141100D01*
G01X1071594Y98188D02*
X1083406D01*
Y110812D01*
X1071594D01*
Y98188D01*
G01X1073713Y100800D02*
X1071287D01*
G01X1066500Y127000D02*
X1060500D01*
Y115000D01*
X1066500D01*
Y127000D01*
G01X1060000Y108200D02*
Y114800D01*
X1047000D01*
Y108200D01*
X1060000D01*
G01X1044900Y127400D02*
X1051100D01*
Y130600D01*
X1044900D01*
Y127400D01*
G01X1051100Y127100D02*
X1044900D01*
Y123900D01*
X1051100D01*
Y127100D01*
G01X1064600Y132100D02*
X1058400D01*
Y128900D01*
X1064600D01*
Y132100D01*
G01X1075100Y115600D02*
X1068900D01*
Y112400D01*
X1075100D01*
Y115600D01*
G01X1055900Y140400D02*
X1062100D01*
Y143600D01*
X1055900D01*
Y140400D01*
G01X1064600Y135600D02*
X1058400D01*
Y132400D01*
X1064600D01*
Y135600D01*
G01X1051100Y135200D02*
X1044900D01*
Y132000D01*
X1051100D01*
Y135200D01*
G01X1044900Y135900D02*
X1051100D01*
Y139100D01*
X1044900D01*
Y135900D01*
G01X1065900Y161100D02*
Y154900D01*
X1069100D01*
Y161100D01*
X1065900D01*
G01X1071600Y184400D02*
Y190600D01*
X1068400D01*
Y184400D01*
X1071600D01*
G01X1073061Y613383D02*
X1072751Y613575D01*
X1072544Y613805D01*
X1072441Y614073D01*
X1072544Y614380D01*
X1072751Y614610D01*
X1073061Y614840D01*
X1073474Y614917D01*
X1075541D01*
G01X1072441Y617250D02*
X1075541D01*
X1074921Y616790D01*
G01X1072441D02*
Y617710D01*
G01Y620350D02*
X1075541D01*
X1074921Y619890D01*
G01X1072441D02*
Y620810D01*
G01X1084043Y97050D02*
Y94828D01*
X1083890Y94363D01*
X1083583Y94053D01*
X1083200Y93950D01*
X1082817Y94053D01*
X1082510Y94363D01*
X1082357Y94828D01*
Y97050D01*
G01X1080943Y94570D02*
X1080713Y94208D01*
X1080407Y94002D01*
X1080062Y93950D01*
X1079755Y94002D01*
X1079448Y94260D01*
X1079257Y94570D01*
X1079218Y94880D01*
X1079295Y95242D01*
X1079563Y95500D01*
X1079832Y95603D01*
X1080177D01*
G01X1079832D02*
X1079602Y95758D01*
X1079410Y96017D01*
X1079333Y96327D01*
X1079410Y96637D01*
X1079602Y96895D01*
X1079947Y97050D01*
X1080292Y96998D01*
X1080637Y96792D01*
G01X1077077Y93950D02*
X1077000Y94622D01*
X1076885Y95190D01*
X1076732Y95707D01*
X1076540Y96275D01*
X1076233Y97050D01*
X1077767D01*
G01X1104043Y96950D02*
Y100050D01*
X1103277D01*
X1102970Y99895D01*
X1102740Y99688D01*
X1102548Y99378D01*
X1102395Y99017D01*
X1102357Y98500D01*
X1102395Y97983D01*
X1102548Y97622D01*
X1102740Y97312D01*
X1102970Y97105D01*
X1103277Y96950D01*
X1104043D01*
G01X1100100D02*
Y100050D01*
X1100560Y99430D01*
G01Y96950D02*
X1099640D01*
G01X1097000D02*
Y100050D01*
X1097460Y99430D01*
G01Y96950D02*
X1096540D01*
G01X1124173Y112748D02*
X1094614D01*
Y101252D01*
X1124173D01*
Y112748D01*
G01X1075900Y118600D02*
Y112400D01*
X1079100D01*
Y118600D01*
X1075900D01*
G01X1090973Y107400D02*
X1093213D01*
G01X1092000Y105775D02*
Y109025D01*
G01X1081043Y151050D02*
Y148828D01*
X1080890Y148363D01*
X1080583Y148053D01*
X1080200Y147950D01*
X1079817Y148053D01*
X1079510Y148363D01*
X1079357Y148828D01*
Y151050D01*
G01X1076640Y147950D02*
Y151050D01*
X1078058Y148828D01*
X1076142D01*
G01X1074000Y151050D02*
X1074307Y150947D01*
X1074537Y150688D01*
X1074690Y150378D01*
X1074805Y149965D01*
X1074843Y149500D01*
X1074805Y149035D01*
X1074690Y148622D01*
X1074537Y148312D01*
X1074307Y148053D01*
X1074000Y147950D01*
X1073693Y148053D01*
X1073463Y148312D01*
X1073310Y148622D01*
X1073195Y149035D01*
X1073157Y149500D01*
X1073195Y149965D01*
X1073310Y150378D01*
X1073463Y150688D01*
X1073693Y150947D01*
X1074000Y151050D01*
G01X1093906Y159312D02*
X1082094D01*
Y146688D01*
X1093906D01*
Y159312D01*
G01X1081000Y138300D02*
Y131700D01*
X1094000D01*
Y138300D01*
X1081000D01*
G01X1092600Y169100D02*
X1086400D01*
Y165900D01*
X1092600D01*
Y169100D01*
G01Y176100D02*
X1086400D01*
Y172900D01*
X1092600D01*
Y176100D01*
G01X1105100Y166600D02*
X1098900D01*
Y163400D01*
X1105100D01*
Y166600D01*
G01X1098900Y178400D02*
X1105100D01*
Y181600D01*
X1098900D01*
Y178400D01*
G01Y181900D02*
X1105100D01*
Y185100D01*
X1098900D01*
Y181900D01*
G01X1078600Y179900D02*
Y186100D01*
X1075400D01*
Y179900D01*
X1078600D01*
G01X1105100Y170100D02*
X1098900D01*
Y166900D01*
X1105100D01*
Y170100D01*
G01X1084100Y179900D02*
Y186100D01*
X1080900D01*
Y179900D01*
X1084100D01*
G01X1075100Y184400D02*
Y190600D01*
X1071900D01*
Y184400D01*
X1075100D01*
G01X1092600Y165600D02*
X1086400D01*
Y162400D01*
X1092600D01*
Y165600D01*
G01Y172600D02*
X1086400D01*
Y169400D01*
X1092600D01*
Y172600D01*
G01X1091043Y372043D02*
Y361843D01*
X1095643D01*
Y372043D01*
X1091043D01*
G01X1088443Y346243D02*
X1078243D01*
Y341643D01*
X1088443D01*
Y346243D01*
G01Y354743D02*
X1078243D01*
Y350143D01*
X1088443D01*
Y354743D01*
G01X1089700Y352000D02*
Y341800D01*
X1094300D01*
Y352000D01*
X1089700D01*
G01X1081943Y365043D02*
X1075743D01*
Y361843D01*
X1081943D01*
Y365043D01*
G01X1075743Y357843D02*
X1081943D01*
Y361043D01*
X1075743D01*
Y357843D01*
G01X1091500Y356773D02*
Y359013D01*
G01X1093125Y357800D02*
X1089875D01*
G01X1075500Y366883D02*
X1078600D01*
Y367803D01*
X1078445Y368110D01*
X1078083Y368340D01*
X1077670Y368417D01*
X1077257Y368340D01*
X1076947Y368148D01*
X1076792Y367803D01*
Y366883D01*
G01X1075500Y369907D02*
X1078600D01*
Y370673D01*
X1078445Y370980D01*
X1078238Y371210D01*
X1077928Y371402D01*
X1077567Y371555D01*
X1077050Y371593D01*
X1076533Y371555D01*
X1076172Y371402D01*
X1075862Y371210D01*
X1075655Y370980D01*
X1075500Y370673D01*
Y369907D01*
G01Y373850D02*
X1078600D01*
X1077980Y373390D01*
G01X1075500D02*
Y374310D01*
G01Y377410D02*
X1078600D01*
X1076378Y375992D01*
Y377908D01*
G01X1089143Y357443D02*
Y371943D01*
X1083543D01*
Y357443D01*
X1089143D01*
G01X1088312Y362762D02*
X1084374D01*
X1086343Y364730D01*
X1088312Y362762D01*
G01Y365124D02*
X1084374D01*
G01X1097100Y355600D02*
X1090900D01*
Y352400D01*
X1097100D01*
Y355600D01*
G01X1088443Y394800D02*
X1078243D01*
Y390200D01*
X1088443D01*
Y394800D01*
G01X1088700Y399600D02*
Y389400D01*
X1093300D01*
Y399600D01*
X1088700D01*
G01X1086443Y372730D02*
Y375156D01*
G01X1089043Y371443D02*
X1083643D01*
G01Y370943D02*
X1089043D01*
G01Y370443D02*
X1083643D01*
G01X1091043Y419543D02*
Y409343D01*
X1095643D01*
Y419543D01*
X1091043D01*
G01X1088443Y402243D02*
X1078243D01*
Y397643D01*
X1088443D01*
Y402243D01*
G01X1075200Y411600D02*
Y405400D01*
X1078400D01*
Y411600D01*
X1075200D01*
G01X1078700D02*
Y405400D01*
X1081900D01*
Y411600D01*
X1078700D01*
G01X1091650Y404173D02*
Y406413D01*
G01X1093275Y405200D02*
X1090025D01*
G01X1086443Y420230D02*
Y422656D01*
G01X1079000Y413883D02*
X1082100D01*
Y414803D01*
X1081945Y415110D01*
X1081583Y415340D01*
X1081170Y415417D01*
X1080757Y415340D01*
X1080447Y415148D01*
X1080292Y414803D01*
Y413883D01*
G01X1079000Y416907D02*
X1082100D01*
Y417673D01*
X1081945Y417980D01*
X1081738Y418210D01*
X1081428Y418402D01*
X1081067Y418555D01*
X1080550Y418593D01*
X1080033Y418555D01*
X1079672Y418402D01*
X1079362Y418210D01*
X1079155Y417980D01*
X1079000Y417673D01*
Y416907D01*
G01Y420850D02*
X1082100D01*
X1081480Y420390D01*
G01X1079000D02*
Y421310D01*
G01X1079465Y423107D02*
X1079207Y423337D01*
X1079052Y423605D01*
X1079000Y423950D01*
X1079103Y424295D01*
X1079310Y424563D01*
X1079672Y424755D01*
X1080085Y424793D01*
X1080498Y424717D01*
X1080757Y424525D01*
X1080963Y424257D01*
X1081015Y423988D01*
X1080963Y423720D01*
X1080757Y423375D01*
X1082100Y423490D01*
Y424525D01*
G01X1089043Y418943D02*
X1083643D01*
G01Y418443D02*
X1089043D01*
G01Y417943D02*
X1083643D01*
G01X1089143Y404943D02*
Y419443D01*
X1083543D01*
Y404943D01*
X1089143D01*
G01X1088312Y410262D02*
X1084374D01*
X1086343Y412230D01*
X1088312Y410262D01*
G01Y412624D02*
X1084374D01*
G01X1097100Y403100D02*
X1090900D01*
Y399900D01*
X1097100D01*
Y403100D01*
G01X1077233Y620655D02*
Y594429D01*
X1111809Y607542D01*
X1077233Y620655D01*
G01X1113800Y127500D02*
X1107200D01*
Y114500D01*
X1113800D01*
Y127500D01*
G01X1127713Y107300D02*
X1125287D01*
G01X1123043Y164550D02*
Y162328D01*
X1122890Y161863D01*
X1122583Y161553D01*
X1122200Y161450D01*
X1121817Y161553D01*
X1121510Y161863D01*
X1121357Y162328D01*
Y164550D01*
G01X1119943Y162070D02*
X1119713Y161708D01*
X1119407Y161502D01*
X1119062Y161450D01*
X1118755Y161502D01*
X1118448Y161760D01*
X1118257Y162070D01*
X1118218Y162380D01*
X1118295Y162742D01*
X1118563Y163000D01*
X1118832Y163103D01*
X1119177D01*
G01X1118832D02*
X1118602Y163258D01*
X1118410Y163517D01*
X1118333Y163827D01*
X1118410Y164137D01*
X1118602Y164395D01*
X1118947Y164550D01*
X1119292Y164498D01*
X1119637Y164292D01*
G01X1116652Y161812D02*
X1116383Y161553D01*
X1116077Y161450D01*
X1115770Y161553D01*
X1115502Y161863D01*
X1115310Y162328D01*
X1115233Y162793D01*
Y163362D01*
X1115310Y163827D01*
X1115502Y164240D01*
X1115732Y164447D01*
X1116000Y164550D01*
X1116307Y164447D01*
X1116537Y164240D01*
X1116690Y163930D01*
X1116767Y163517D01*
X1116690Y163155D01*
X1116498Y162793D01*
X1116268Y162587D01*
X1116000Y162535D01*
X1115693Y162638D01*
X1115463Y162897D01*
X1115233Y163362D01*
G01X1103688Y160406D02*
Y148594D01*
X1116312D01*
Y160406D01*
X1103688D01*
G01X1112400Y146600D02*
Y140400D01*
X1115600D01*
Y146600D01*
X1112400D01*
G01X1111600Y140400D02*
Y146600D01*
X1108400D01*
Y140400D01*
X1111600D01*
G01X1102900Y144600D02*
Y138400D01*
X1106100D01*
Y144600D01*
X1102900D01*
G01X1128145Y152861D02*
Y150621D01*
G01X1126520Y151834D02*
X1129770D01*
G01X1133600Y175900D02*
Y182100D01*
X1130400D01*
Y175900D01*
X1133600D01*
G01X1130500Y211200D02*
Y217800D01*
X1117500D01*
Y211200D01*
X1130500D01*
G01X1146094Y89000D02*
Y92100D01*
X1146554Y91480D01*
G01Y89000D02*
X1145634D01*
G01X1143100Y112900D02*
Y119100D01*
X1139900D01*
Y112900D01*
X1143100D01*
G01X1140050Y133957D02*
X1137828D01*
X1137363Y134110D01*
X1137053Y134417D01*
X1136950Y134800D01*
X1137053Y135183D01*
X1137363Y135490D01*
X1137828Y135643D01*
X1140050D01*
G01X1137570Y137057D02*
X1137208Y137287D01*
X1137002Y137593D01*
X1136950Y137938D01*
X1137002Y138245D01*
X1137260Y138552D01*
X1137570Y138743D01*
X1137880Y138782D01*
X1138242Y138705D01*
X1138500Y138437D01*
X1138603Y138168D01*
Y137823D01*
G01Y138168D02*
X1138758Y138398D01*
X1139017Y138590D01*
X1139327Y138667D01*
X1139637Y138590D01*
X1139895Y138398D01*
X1140050Y138053D01*
X1139998Y137708D01*
X1139792Y137363D01*
G01X1138242Y140272D02*
X1138603Y140540D01*
X1138810Y140770D01*
X1138913Y141077D01*
X1138810Y141345D01*
X1138603Y141537D01*
X1138293Y141690D01*
X1137932Y141728D01*
X1137622Y141690D01*
X1137312Y141537D01*
X1137053Y141307D01*
X1136950Y141038D01*
X1137053Y140732D01*
X1137363Y140463D01*
X1137828Y140310D01*
X1138345Y140272D01*
X1139017Y140348D01*
X1139378Y140463D01*
X1139740Y140655D01*
X1139998Y140923D01*
X1140050Y141192D01*
X1139947Y141460D01*
X1139688Y141652D01*
G01X1142188Y143906D02*
Y132094D01*
X1154812D01*
Y143906D01*
X1142188D01*
G01X1136195Y142134D02*
X1142395D01*
Y145334D01*
X1136195D01*
Y142134D01*
G01X1148900Y152400D02*
X1155100D01*
Y155600D01*
X1148900D01*
Y152400D01*
G01X1152984Y149784D02*
X1150558D01*
G01X1147188Y153384D02*
Y156484D01*
X1146422D01*
X1146115Y156329D01*
X1145885Y156122D01*
X1145693Y155812D01*
X1145540Y155451D01*
X1145502Y154934D01*
X1145540Y154417D01*
X1145693Y154056D01*
X1145885Y153746D01*
X1146115Y153539D01*
X1146422Y153384D01*
X1147188D01*
G01X1143973Y154676D02*
X1143705Y155037D01*
X1143475Y155244D01*
X1143168Y155347D01*
X1142900Y155244D01*
X1142708Y155037D01*
X1142555Y154727D01*
X1142517Y154366D01*
X1142555Y154056D01*
X1142708Y153746D01*
X1142938Y153487D01*
X1143207Y153384D01*
X1143513Y153487D01*
X1143782Y153797D01*
X1143935Y154262D01*
X1143973Y154779D01*
X1143897Y155451D01*
X1143782Y155812D01*
X1143590Y156174D01*
X1143322Y156432D01*
X1143053Y156484D01*
X1142785Y156381D01*
X1142593Y156122D01*
G01X1138090Y147765D02*
Y151703D01*
X1140058Y149734D01*
X1138090Y147765D01*
G01X1140452D02*
Y151703D01*
G01X1147421Y147084D02*
Y146984D01*
X1148071D01*
Y152484D01*
X1147371D01*
Y152234D01*
X1147771D01*
Y146984D01*
X1148521D01*
Y152484D01*
X1148021D01*
G01X1131221Y146978D02*
X1147369D01*
Y152490D01*
X1131221D01*
Y146978D01*
G01X1157000Y173700D02*
Y180300D01*
X1144000D01*
Y173700D01*
X1157000D01*
G01X1145160Y172920D02*
Y166720D01*
X1148360D01*
Y172920D01*
X1145160D01*
G01X1151300Y216500D02*
X1144700D01*
Y203500D01*
X1151300D01*
Y216500D01*
G01X1143800D02*
X1137200D01*
Y203500D01*
X1143800D01*
Y216500D01*
G01X1158800D02*
X1152200D01*
Y203500D01*
X1158800D01*
Y216500D01*
G01X1142100Y198100D02*
X1135900D01*
Y194900D01*
X1142100D01*
Y198100D01*
G01Y202100D02*
X1135900D01*
Y198900D01*
X1142100D01*
Y202100D01*
G01X1176837Y89620D02*
X1176607Y89258D01*
X1176301Y89052D01*
X1175956Y89000D01*
X1175649Y89052D01*
X1175342Y89310D01*
X1175151Y89620D01*
X1175112Y89930D01*
X1175189Y90292D01*
X1175457Y90550D01*
X1175726Y90653D01*
X1176071D01*
G01X1175726D02*
X1175496Y90808D01*
X1175304Y91067D01*
X1175227Y91377D01*
X1175304Y91687D01*
X1175496Y91945D01*
X1175841Y92100D01*
X1176186Y92048D01*
X1176531Y91842D01*
G01X1183639Y114500D02*
Y117600D01*
X1182719D01*
X1182412Y117445D01*
X1182182Y117083D01*
X1182105Y116670D01*
X1182182Y116257D01*
X1182374Y115947D01*
X1182719Y115792D01*
X1183639D01*
G01X1180615Y114500D02*
Y117600D01*
X1179849D01*
X1179542Y117445D01*
X1179312Y117238D01*
X1179120Y116928D01*
X1178967Y116567D01*
X1178929Y116050D01*
X1178967Y115533D01*
X1179120Y115172D01*
X1179312Y114862D01*
X1179542Y114655D01*
X1179849Y114500D01*
X1180615D01*
G01X1177400Y115792D02*
X1177132Y116153D01*
X1176902Y116360D01*
X1176595Y116463D01*
X1176327Y116360D01*
X1176135Y116153D01*
X1175982Y115843D01*
X1175944Y115482D01*
X1175982Y115172D01*
X1176135Y114862D01*
X1176365Y114603D01*
X1176634Y114500D01*
X1176940Y114603D01*
X1177209Y114913D01*
X1177362Y115378D01*
X1177400Y115895D01*
X1177324Y116567D01*
X1177209Y116928D01*
X1177017Y117290D01*
X1176749Y117548D01*
X1176480Y117600D01*
X1176212Y117497D01*
X1176020Y117238D01*
G01X1171317Y162235D02*
Y125095D01*
X1195805D01*
Y162135D01*
G01X1171317Y162335D02*
Y157455D01*
G01Y159822D02*
Y159928D01*
G01X1183561Y139259D02*
Y141059D01*
G01X1179561Y141459D02*
X1187561D01*
X1183561Y146459D01*
X1179561Y141459D01*
G01X1178561Y146459D02*
X1188561D01*
G01X1183561D02*
Y148259D01*
G01X1170900Y199800D02*
X1164300D01*
Y186800D01*
X1170900D01*
Y199800D01*
G01X1195805Y163578D02*
X1171317D01*
G01X1195805Y163178D02*
X1171317D01*
G01X1195805Y162878D02*
X1171317D01*
G01Y162135D02*
Y164759D01*
X1175500D01*
G01X1195805Y161984D02*
X1171317D01*
G01Y162135D02*
Y161609D01*
G01X1195805Y161984D02*
X1171317D01*
G01X1195805Y161945D02*
X1171317D01*
G01X1195805Y161984D02*
X1171317D01*
G01X1195805Y162378D02*
X1171317D01*
G01X1171610Y162022D02*
X1171810Y162009D01*
G01X1179200Y164759D02*
X1186800D01*
G01X1175700Y164378D02*
X1171317D01*
G01X1175700Y164178D02*
X1171317D01*
G01X1175700Y163978D02*
X1171317D01*
G01X1186800D02*
X1179200D01*
G01X1186800Y164178D02*
X1179200D01*
G01X1186800Y164378D02*
X1179200D01*
G01X1198981Y126525D02*
Y124285D01*
G01X1197356Y125498D02*
X1200606D01*
G01X1200552Y422224D02*
X1281575D01*
Y151634D01*
X1200552D01*
Y422224D01*
G01X1195805Y161609D02*
Y160322D01*
G01Y161222D02*
Y160022D01*
G01Y159928D02*
Y162335D01*
G01X1195522Y169913D02*
Y167487D01*
G01X1195805Y164378D02*
X1190500D01*
G01X1195805Y164178D02*
X1190500D01*
G01X1195805Y163978D02*
X1190500D01*
G01Y164759D02*
X1195805D01*
Y162290D01*
G01X1217879Y189096D02*
Y192196D01*
G01X1216269D02*
Y189096D01*
G01Y190646D02*
X1217879D01*
G01X1214702Y191679D02*
X1214472Y191989D01*
X1214204Y192144D01*
X1213897Y192196D01*
X1213514Y192093D01*
X1213246Y191834D01*
X1213169Y191524D01*
X1213207Y191214D01*
X1213361Y190956D01*
X1214127Y190439D01*
X1214472Y190078D01*
X1214702Y189561D01*
X1214779Y189096D01*
X1213169D01*
G01X1211717Y189561D02*
X1211487Y189303D01*
X1211219Y189148D01*
X1210874Y189096D01*
X1210529Y189199D01*
X1210261Y189406D01*
X1210069Y189768D01*
X1210031Y190181D01*
X1210107Y190594D01*
X1210299Y190853D01*
X1210567Y191059D01*
X1210836Y191111D01*
X1211104Y191059D01*
X1211449Y190853D01*
X1211334Y192196D01*
X1210299D01*
G01X1217879Y414096D02*
Y417196D01*
G01X1216269D02*
Y414096D01*
G01Y415646D02*
X1217879D01*
G01X1214702Y416679D02*
X1214472Y416989D01*
X1214204Y417144D01*
X1213897Y417196D01*
X1213514Y417093D01*
X1213246Y416834D01*
X1213169Y416524D01*
X1213207Y416214D01*
X1213361Y415956D01*
X1214127Y415439D01*
X1214472Y415078D01*
X1214702Y414561D01*
X1214779Y414096D01*
X1213169D01*
G01X1210414D02*
Y417196D01*
X1211832Y414974D01*
X1209916D01*
G01X1272374Y255112D02*
X1279874D01*
Y257352D01*
X1279499Y258099D01*
X1278624Y258659D01*
X1277624Y258846D01*
X1276624Y258659D01*
X1275874Y258192D01*
X1275499Y257352D01*
Y255112D01*
G01X1272374Y262612D02*
X1279874D01*
Y264946D01*
X1279499Y265692D01*
X1278999Y266159D01*
X1277999Y266346D01*
X1276999Y266159D01*
X1276374Y265599D01*
X1275999Y264946D01*
Y262612D01*
G01Y264946D02*
X1272374Y266346D01*
G01Y273846D02*
Y270112D01*
X1279874D01*
Y273846D01*
G01X1276249Y272352D02*
Y270112D01*
G01X1273374Y277519D02*
X1272749Y278266D01*
X1272374Y279106D01*
Y279852D01*
X1272749Y280599D01*
X1273374Y281159D01*
X1274249Y281439D01*
X1275124Y281252D01*
X1275874Y280786D01*
X1276374Y279946D01*
X1276624Y278826D01*
X1277124Y278172D01*
X1277999Y277892D01*
X1278874Y278079D01*
X1279499Y278546D01*
X1279874Y279199D01*
Y279852D01*
X1279624Y280506D01*
X1278999Y281066D01*
G01X1273374Y285019D02*
X1272749Y285766D01*
X1272374Y286606D01*
Y287352D01*
X1272749Y288099D01*
X1273374Y288659D01*
X1274249Y288939D01*
X1275124Y288752D01*
X1275874Y288286D01*
X1276374Y287446D01*
X1276624Y286326D01*
X1277124Y285672D01*
X1277999Y285392D01*
X1278874Y285579D01*
X1279499Y286046D01*
X1279874Y286699D01*
Y287352D01*
X1279624Y288006D01*
X1278999Y288566D01*
G01X1274874Y293266D02*
Y295692D01*
G01X1272374Y300206D02*
X1279874D01*
Y303752D01*
G01X1276249Y302446D02*
Y300206D01*
G01X1279874Y308359D02*
Y310599D01*
G01Y309479D02*
X1272374D01*
G01Y308359D02*
Y310599D01*
G01X1279874Y316979D02*
X1272374D01*
G01X1279874Y314832D02*
Y319126D01*
M02*
